FILE_TYPE = MACRO_DRAWING;
SET COLOR_WIRE YELLOW;
SET COLOR_PROP MONO;
SET COLOR_DOT WHITE;
SET COLOR_ARC YELLOW;
SET COLOR_BODY GREEN;
SET COLOR_NOTE MONO;
SET PROP_DISPLAY VALUE;
SET PAGE_NUMBER P105;
FORCEADD CAP..1
R 2
(1125 3650);
FORCEPROP 1 LAST LOCATION C7G24
J 2
(1075 3750);
DISPLAY 0.617021 (1075 3750);
PAINT AQUA (1075 3750);
FORCEPROP 1 LAST PART_NUMBER A36096-155
J 2
(1075 3500);
DISPLAY 0.617021 (1075 3500);
PAINT BLUE (1075 3500);
FORCEPROP 1 LAST VALUE 0.22UF
J 2
(1075 3700);
DISPLAY 0.617021 (1075 3700);
PAINT SKYBLUE (1075 3700);
FORCEPROP 1 LAST TOLERANCE 10%
J 2
(1075 3600);
DISPLAY 0.617021 (1075 3600);
PAINT SKYBLUE (1075 3600);
FORCEPROP 1 LAST PACK_TYPE 0402
J 2
(1075 3450);
DISPLAY 0.617021 (1075 3450);
PAINT SKYBLUE (1075 3450);
FORCEPROP 1 LAST VOLTAGE 16V
J 2
(1075 3650);
DISPLAY 0.617021 (1075 3650);
PAINT SKYBLUE (1075 3650);
FORCEPROP 1 LAST MATERIAL X7R
J 2
(1075 3550);
DISPLAY 0.617021 (1075 3550);
PAINT SKYBLUE (1075 3550);
FORCEPROP 1 LASTPIN (1125 3550) $PN 2
J 2
(1115 3530);
DISPLAY 0.617021 (1115 3530);
PAINT ORANGE (1115 3530);
FORCEPROP 1 LASTPIN (1125 3750) $PN 1
J 2
(1115 3730);
DISPLAY 0.617021 (1115 3730);
PAINT ORANGE (1115 3730);
FORCEPROP 2 LAST CDS_LIB mstr_discrete
J 0
(1125 3650);
PAINT ORANGE (1125 3650);
DISPLAY INVISIBLE (1125 3650);
FORCEPROP 2 LAST SEC_TYPE 0402
J 0
(1075 3850);
DISPLAY 1.021277 (1075 3850);
PAINT ORANGE (1075 3850);
DISPLAY INVISIBLE (1075 3850);
FORCEPROP 2 LAST SEC 1
J 0
(1075 3850);
DISPLAY 0.680851 (1075 3850);
PAINT MONO (1075 3850);
DISPLAY INVISIBLE (1075 3850);
FORCEPROP 2 LAST CDS_LOCATION C7G24
J 2
(1075 3750);
DISPLAY 0.617021 (1075 3750);
PAINT AQUA (1075 3750);
DISPLAY INVISIBLE (1075 3750);
FORCEPROP 1 LAST PATH I1
J 2
(1075 3800);
DISPLAY 0.978723 (1075 3800);
PAINT WHITE (1075 3800);
DISPLAY INVISIBLE (1075 3800);
FORCEPROP 2 LAST ROOM OCP_STEERING
J 2
(1125 3650);
PAINT MONO (1125 3650);
DISPLAY INVISIBLE (1125 3650);
FORCEADD TAP..7
(-100 3100);
FORCEPROP 3 LASTPIN (-100 3150) SIG_NAME P3E_CPU0_PE2_SS_C_TXN<12>
J 0
(-90 3160);
DISPLAY 0.659574 (-90 3160);
PAINT MONO (-90 3160);
DISPLAY INVISIBLE (-90 3160);
FORCEPROP 1 LASTPIN (-100 3150) BN 12
R 1
J 0
(-107 3098);
DISPLAY 0.617021 (-107 3098);
PAINT GREEN (-107 3098);
FORCEPROP 2 LAST CDS_LIB mstr_standard
J 0
(-100 3100);
PAINT ORANGE (-100 3100);
DISPLAY INVISIBLE (-100 3100);
FORCEPROP 1 LAST BODY_TYPE PLUMBING
J 0
(-50 3100);
DISPLAY 2.276596 (-50 3100);
PAINT GREEN (-50 3100);
DISPLAY INVISIBLE (-50 3100);
FORCEPROP 1 LAST HDL_TAP TRUE
J 0
(220 2970);
DISPLAY 2.276596 (220 2970);
PAINT GREEN (220 2970);
DISPLAY INVISIBLE (220 2970);
FORCEPROP 1 LAST PATH I10
J 0
(-102 3100);
DISPLAY 0.872340 (-102 3100);
PAINT GREEN (-102 3100);
DISPLAY INVISIBLE (-102 3100);
FORCEADD TAP..7
(100 3100);
FORCEPROP 3 LASTPIN (100 3150) SIG_NAME P3E_CPU0_PE2_SS_C_TXN<11>
J 0
(110 3160);
DISPLAY 0.659574 (110 3160);
PAINT MONO (110 3160);
DISPLAY INVISIBLE (110 3160);
FORCEPROP 1 LASTPIN (100 3150) BN 11
R 1
J 0
(93 3098);
DISPLAY 0.617021 (93 3098);
PAINT GREEN (93 3098);
FORCEPROP 2 LAST CDS_LIB mstr_standard
J 0
(100 3100);
PAINT ORANGE (100 3100);
DISPLAY INVISIBLE (100 3100);
FORCEPROP 1 LAST BODY_TYPE PLUMBING
J 0
(150 3100);
DISPLAY 2.276596 (150 3100);
PAINT GREEN (150 3100);
DISPLAY INVISIBLE (150 3100);
FORCEPROP 1 LAST HDL_TAP TRUE
J 0
(420 2970);
DISPLAY 2.276596 (420 2970);
PAINT GREEN (420 2970);
DISPLAY INVISIBLE (420 2970);
FORCEPROP 1 LAST PATH I11
J 0
(98 3100);
DISPLAY 0.872340 (98 3100);
PAINT GREEN (98 3100);
DISPLAY INVISIBLE (98 3100);
FORCEADD CAP..1
R 2
(-100 3650);
FORCEPROP 1 LAST LOCATION C7G12
J 2
(-150 3750);
DISPLAY 0.617021 (-150 3750);
PAINT AQUA (-150 3750);
FORCEPROP 1 LAST PART_NUMBER A36096-155
J 2
(-150 3500);
DISPLAY 0.617021 (-150 3500);
PAINT BLUE (-150 3500);
FORCEPROP 1 LAST VALUE 0.22UF
J 2
(-150 3700);
DISPLAY 0.617021 (-150 3700);
PAINT SKYBLUE (-150 3700);
FORCEPROP 1 LAST TOLERANCE 10%
J 2
(-150 3600);
DISPLAY 0.617021 (-150 3600);
PAINT SKYBLUE (-150 3600);
FORCEPROP 1 LAST PACK_TYPE 0402
J 2
(-150 3450);
DISPLAY 0.617021 (-150 3450);
PAINT SKYBLUE (-150 3450);
FORCEPROP 1 LAST VOLTAGE 16V
J 2
(-150 3650);
DISPLAY 0.617021 (-150 3650);
PAINT SKYBLUE (-150 3650);
FORCEPROP 1 LAST MATERIAL X7R
J 2
(-150 3550);
DISPLAY 0.617021 (-150 3550);
PAINT SKYBLUE (-150 3550);
FORCEPROP 1 LASTPIN (-100 3550) $PN 2
J 2
(-110 3530);
DISPLAY 0.617021 (-110 3530);
PAINT ORANGE (-110 3530);
FORCEPROP 1 LASTPIN (-100 3750) $PN 1
J 2
(-110 3730);
DISPLAY 0.617021 (-110 3730);
PAINT ORANGE (-110 3730);
FORCEPROP 2 LAST SEC_TYPE 0402
J 0
(-150 3850);
DISPLAY 1.021277 (-150 3850);
PAINT ORANGE (-150 3850);
DISPLAY INVISIBLE (-150 3850);
FORCEPROP 2 LAST CDS_LIB mstr_discrete
J 0
(-100 3650);
PAINT ORANGE (-100 3650);
DISPLAY INVISIBLE (-100 3650);
FORCEPROP 2 LAST SEC 1
J 0
(-150 3850);
DISPLAY 0.680851 (-150 3850);
PAINT MONO (-150 3850);
DISPLAY INVISIBLE (-150 3850);
FORCEPROP 2 LAST CDS_LOCATION C7G12
J 2
(-150 3750);
DISPLAY 0.617021 (-150 3750);
PAINT AQUA (-150 3750);
DISPLAY INVISIBLE (-150 3750);
FORCEPROP 1 LAST PATH I12
J 2
(-150 3800);
DISPLAY 0.978723 (-150 3800);
PAINT WHITE (-150 3800);
DISPLAY INVISIBLE (-150 3800);
FORCEPROP 2 LAST ROOM OCP_STEERING
J 2
(-100 3650);
PAINT MONO (-100 3650);
DISPLAY INVISIBLE (-100 3650);
FORCEADD CAP..1
R 2
(100 3350);
FORCEPROP 1 LAST LOCATION C7G13
J 2
(50 3450);
DISPLAY 0.617021 (50 3450);
PAINT AQUA (50 3450);
FORCEPROP 1 LAST PART_NUMBER A36096-155
J 2
(50 3200);
DISPLAY 0.617021 (50 3200);
PAINT BLUE (50 3200);
FORCEPROP 1 LAST VALUE 0.22UF
J 2
(50 3400);
DISPLAY 0.617021 (50 3400);
PAINT SKYBLUE (50 3400);
FORCEPROP 1 LAST TOLERANCE 10%
J 2
(50 3300);
DISPLAY 0.617021 (50 3300);
PAINT SKYBLUE (50 3300);
FORCEPROP 1 LAST PACK_TYPE 0402
J 2
(50 3150);
DISPLAY 0.617021 (50 3150);
PAINT SKYBLUE (50 3150);
FORCEPROP 1 LAST VOLTAGE 16V
J 2
(50 3350);
DISPLAY 0.617021 (50 3350);
PAINT SKYBLUE (50 3350);
FORCEPROP 1 LAST MATERIAL X7R
J 2
(50 3250);
DISPLAY 0.617021 (50 3250);
PAINT SKYBLUE (50 3250);
FORCEPROP 1 LASTPIN (100 3250) $PN 2
J 2
(90 3230);
DISPLAY 0.617021 (90 3230);
PAINT ORANGE (90 3230);
FORCEPROP 1 LASTPIN (100 3450) $PN 1
J 2
(90 3430);
DISPLAY 0.617021 (90 3430);
PAINT ORANGE (90 3430);
FORCEPROP 2 LAST SEC_TYPE 0402
J 0
(50 3550);
DISPLAY 1.021277 (50 3550);
PAINT ORANGE (50 3550);
DISPLAY INVISIBLE (50 3550);
FORCEPROP 2 LAST CDS_LIB mstr_discrete
J 0
(100 3350);
PAINT ORANGE (100 3350);
DISPLAY INVISIBLE (100 3350);
FORCEPROP 2 LAST SEC 1
J 0
(50 3550);
DISPLAY 0.680851 (50 3550);
PAINT MONO (50 3550);
DISPLAY INVISIBLE (50 3550);
FORCEPROP 2 LAST CDS_LOCATION C7G13
J 2
(50 3450);
DISPLAY 0.617021 (50 3450);
PAINT AQUA (50 3450);
DISPLAY INVISIBLE (50 3450);
FORCEPROP 1 LAST PATH I13
J 2
(50 3500);
DISPLAY 0.978723 (50 3500);
PAINT WHITE (50 3500);
DISPLAY INVISIBLE (50 3500);
FORCEPROP 2 LAST ROOM OCP_STEERING
J 2
(100 3350);
PAINT MONO (100 3350);
DISPLAY INVISIBLE (100 3350);
FORCEADD TAP..3
(-700 3900);
FORCEPROP 3 LASTPIN (-700 3850) SIG_NAME P3E_CPU0_PE2_SS_TXN<15>
J 0
(-690 3860);
DISPLAY 0.659574 (-690 3860);
PAINT MONO (-690 3860);
DISPLAY INVISIBLE (-690 3860);
FORCEPROP 1 LASTPIN (-700 3850) BN 15
R 1
J 0
(-707 3838);
DISPLAY 0.617021 (-707 3838);
PAINT GREEN (-707 3838);
FORCEPROP 2 LAST CDS_LIB mstr_standard
J 0
(-700 3900);
PAINT ORANGE (-700 3900);
DISPLAY INVISIBLE (-700 3900);
FORCEPROP 1 LAST BODY_TYPE PLUMBING
J 0
(-650 3850);
DISPLAY 2.276596 (-650 3850);
PAINT GREEN (-650 3850);
DISPLAY INVISIBLE (-650 3850);
FORCEPROP 1 LAST HDL_TAP TRUE
J 0
(-380 3770);
DISPLAY 2.276596 (-380 3770);
PAINT GREEN (-380 3770);
DISPLAY INVISIBLE (-380 3770);
FORCEPROP 1 LAST PATH I14
J 0
(-702 3900);
DISPLAY 0.872340 (-702 3900);
PAINT GREEN (-702 3900);
DISPLAY INVISIBLE (-702 3900);
FORCEADD TAP..7
(-750 4100);
FORCEPROP 3 LASTPIN (-750 4150) SIG_NAME P3E_CPU0_PE2_SS_C_TXP<15>
J 0
(-740 4160);
DISPLAY 0.659574 (-740 4160);
PAINT MONO (-740 4160);
DISPLAY INVISIBLE (-740 4160);
FORCEPROP 1 LASTPIN (-750 4150) BN 15
R 1
J 0
(-757 4098);
DISPLAY 0.617021 (-757 4098);
PAINT GREEN (-757 4098);
FORCEPROP 2 LAST CDS_LIB mstr_standard
J 0
(-750 4100);
PAINT ORANGE (-750 4100);
DISPLAY INVISIBLE (-750 4100);
FORCEPROP 1 LAST BODY_TYPE PLUMBING
J 0
(-700 4100);
DISPLAY 2.276596 (-700 4100);
PAINT GREEN (-700 4100);
DISPLAY INVISIBLE (-700 4100);
FORCEPROP 1 LAST HDL_TAP TRUE
J 0
(-430 3970);
DISPLAY 2.276596 (-430 3970);
PAINT GREEN (-430 3970);
DISPLAY INVISIBLE (-430 3970);
FORCEPROP 1 LAST PATH I15
J 0
(-752 4100);
DISPLAY 0.872340 (-752 4100);
PAINT GREEN (-752 4100);
DISPLAY INVISIBLE (-752 4100);
FORCEADD TAP..3
(1925 3900);
FORCEPROP 3 LASTPIN (1925 3850) SIG_NAME P3E_CPU0_PE2_SS_TXN<2>
J 0
(1935 3860);
DISPLAY 0.659574 (1935 3860);
PAINT MONO (1935 3860);
DISPLAY INVISIBLE (1935 3860);
FORCEPROP 1 LASTPIN (1925 3850) BN 2
R 1
J 0
(1918 3838);
DISPLAY 0.617021 (1918 3838);
PAINT GREEN (1918 3838);
FORCEPROP 2 LAST CDS_LIB mstr_standard
J 0
(1925 3900);
PAINT ORANGE (1925 3900);
DISPLAY INVISIBLE (1925 3900);
FORCEPROP 1 LAST BODY_TYPE PLUMBING
J 0
(1975 3850);
DISPLAY 2.276596 (1975 3850);
PAINT GREEN (1975 3850);
DISPLAY INVISIBLE (1975 3850);
FORCEPROP 1 LAST HDL_TAP TRUE
J 0
(2245 3770);
DISPLAY 2.276596 (2245 3770);
PAINT GREEN (2245 3770);
DISPLAY INVISIBLE (2245 3770);
FORCEPROP 1 LAST PATH I151
J 0
(1923 3900);
DISPLAY 0.872340 (1923 3900);
PAINT GREEN (1923 3900);
DISPLAY INVISIBLE (1923 3900);
FORCEADD TAP..3
(50 4900);
FORCEPROP 3 LASTPIN (50 4850) SIG_NAME P3E_CPU0_PE2_SS_TXP<11>
J 0
(60 4860);
DISPLAY 0.659574 (60 4860);
PAINT MONO (60 4860);
DISPLAY INVISIBLE (60 4860);
FORCEPROP 1 LASTPIN (50 4850) BN 11
R 1
J 0
(43 4838);
DISPLAY 0.617021 (43 4838);
PAINT GREEN (43 4838);
FORCEPROP 2 LAST CDS_LIB mstr_standard
J 0
(50 4900);
PAINT ORANGE (50 4900);
DISPLAY INVISIBLE (50 4900);
FORCEPROP 1 LAST BODY_TYPE PLUMBING
J 0
(100 4850);
DISPLAY 2.276596 (100 4850);
PAINT GREEN (100 4850);
DISPLAY INVISIBLE (100 4850);
FORCEPROP 1 LAST HDL_TAP TRUE
J 0
(370 4770);
DISPLAY 2.276596 (370 4770);
PAINT GREEN (370 4770);
DISPLAY INVISIBLE (370 4770);
FORCEPROP 1 LAST PATH I152
J 0
(48 4900);
DISPLAY 0.872340 (48 4900);
PAINT GREEN (48 4900);
DISPLAY INVISIBLE (48 4900);
FORCEADD CAP..1
R 2
(-1500 975);
FORCEPROP 1 LAST LOCATION C6B18
J 2
(-1550 1075);
DISPLAY 0.617021 (-1550 1075);
PAINT AQUA (-1550 1075);
FORCEPROP 1 LAST PART_NUMBER A36096-155
J 2
(-1550 825);
DISPLAY 0.617021 (-1550 825);
PAINT BLUE (-1550 825);
FORCEPROP 1 LAST VALUE 0.22UF
J 2
(-1550 1025);
DISPLAY 0.617021 (-1550 1025);
PAINT SKYBLUE (-1550 1025);
FORCEPROP 1 LAST TOLERANCE 10%
J 2
(-1550 925);
DISPLAY 0.617021 (-1550 925);
PAINT SKYBLUE (-1550 925);
FORCEPROP 1 LAST PACK_TYPE 0402
J 2
(-1550 775);
DISPLAY 0.617021 (-1550 775);
PAINT SKYBLUE (-1550 775);
FORCEPROP 1 LAST VOLTAGE 16V
J 2
(-1550 975);
DISPLAY 0.617021 (-1550 975);
PAINT SKYBLUE (-1550 975);
FORCEPROP 1 LAST MATERIAL X7R
J 2
(-1550 875);
DISPLAY 0.617021 (-1550 875);
PAINT SKYBLUE (-1550 875);
FORCEPROP 1 LASTPIN (-1500 875) $PN 2
J 2
(-1510 855);
DISPLAY 0.617021 (-1510 855);
PAINT ORANGE (-1510 855);
FORCEPROP 1 LASTPIN (-1500 1075) $PN 1
J 2
(-1510 1055);
DISPLAY 0.617021 (-1510 1055);
PAINT ORANGE (-1510 1055);
FORCEPROP 2 LAST SEC_TYPE 0402
J 0
(-1550 1175);
DISPLAY 1.021277 (-1550 1175);
PAINT ORANGE (-1550 1175);
DISPLAY INVISIBLE (-1550 1175);
FORCEPROP 2 LAST CDS_LIB mstr_discrete
J 0
(-1500 975);
PAINT ORANGE (-1500 975);
DISPLAY INVISIBLE (-1500 975);
FORCEPROP 2 LAST SEC 1
J 0
(-1550 1175);
DISPLAY 0.680851 (-1550 1175);
PAINT MONO (-1550 1175);
DISPLAY INVISIBLE (-1550 1175);
FORCEPROP 2 LAST CDS_LOCATION C6B18
J 2
(-1550 1075);
DISPLAY 0.617021 (-1550 1075);
PAINT AQUA (-1550 1075);
DISPLAY INVISIBLE (-1550 1075);
FORCEPROP 1 LAST PATH I153
J 2
(-1550 1125);
DISPLAY 0.978723 (-1550 1125);
PAINT WHITE (-1550 1125);
DISPLAY INVISIBLE (-1550 1125);
FORCEPROP 2 LAST ROOM OCP_STEERING
J 2
(-1500 975);
PAINT MONO (-1500 975);
DISPLAY INVISIBLE (-1500 975);
FORCEADD TAP..7
(-1350 1725);
FORCEPROP 3 LASTPIN (-1350 1775) SIG_NAME P3E_CPU0_PE1_PCH_C_TXN<8>
J 0
(-1340 1785);
DISPLAY 0.659574 (-1340 1785);
PAINT MONO (-1340 1785);
DISPLAY INVISIBLE (-1340 1785);
FORCEPROP 1 LASTPIN (-1350 1775) BN 8
R 1
J 0
(-1357 1723);
DISPLAY 0.617021 (-1357 1723);
PAINT GREEN (-1357 1723);
FORCEPROP 2 LAST CDS_LIB mstr_standard
J 0
(-1350 1725);
PAINT ORANGE (-1350 1725);
DISPLAY INVISIBLE (-1350 1725);
FORCEPROP 1 LAST BODY_TYPE PLUMBING
J 0
(-1300 1725);
DISPLAY 2.276596 (-1300 1725);
PAINT GREEN (-1300 1725);
DISPLAY INVISIBLE (-1300 1725);
FORCEPROP 1 LAST HDL_TAP TRUE
J 0
(-1030 1595);
DISPLAY 2.276596 (-1030 1595);
PAINT GREEN (-1030 1595);
DISPLAY INVISIBLE (-1030 1595);
FORCEPROP 1 LAST PATH I154
J 0
(-1352 1725);
DISPLAY 0.872340 (-1352 1725);
PAINT GREEN (-1352 1725);
DISPLAY INVISIBLE (-1352 1725);
FORCEADD TAP..3
(-2100 1525);
FORCEPROP 3 LASTPIN (-2100 1475) SIG_NAME P3E_CPU0_PE1_PCH_TXP<12>
J 0
(-2090 1485);
DISPLAY 0.659574 (-2090 1485);
PAINT MONO (-2090 1485);
DISPLAY INVISIBLE (-2090 1485);
FORCEPROP 1 LASTPIN (-2100 1475) BN 12
R 1
J 0
(-2107 1463);
DISPLAY 0.617021 (-2107 1463);
PAINT GREEN (-2107 1463);
FORCEPROP 2 LAST CDS_LIB mstr_standard
J 0
(-2100 1525);
PAINT ORANGE (-2100 1525);
DISPLAY INVISIBLE (-2100 1525);
FORCEPROP 1 LAST BODY_TYPE PLUMBING
J 0
(-2050 1475);
DISPLAY 2.276596 (-2050 1475);
PAINT GREEN (-2050 1475);
DISPLAY INVISIBLE (-2050 1475);
FORCEPROP 1 LAST HDL_TAP TRUE
J 0
(-1780 1395);
DISPLAY 2.276596 (-1780 1395);
PAINT GREEN (-1780 1395);
DISPLAY INVISIBLE (-1780 1395);
FORCEPROP 1 LAST PATH I155
J 0
(-2102 1525);
DISPLAY 0.872340 (-2102 1525);
PAINT GREEN (-2102 1525);
DISPLAY INVISIBLE (-2102 1525);
FORCEADD TAP..7
(-2350 1725);
FORCEPROP 3 LASTPIN (-2350 1775) SIG_NAME P3E_CPU0_PE1_PCH_C_TXN<13>
J 0
(-2340 1785);
DISPLAY 0.659574 (-2340 1785);
PAINT MONO (-2340 1785);
DISPLAY INVISIBLE (-2340 1785);
FORCEPROP 1 LASTPIN (-2350 1775) BN 13
R 1
J 0
(-2357 1723);
DISPLAY 0.617021 (-2357 1723);
PAINT GREEN (-2357 1723);
FORCEPROP 2 LAST CDS_LIB mstr_standard
J 0
(-2350 1725);
PAINT ORANGE (-2350 1725);
DISPLAY INVISIBLE (-2350 1725);
FORCEPROP 1 LAST BODY_TYPE PLUMBING
J 0
(-2300 1725);
DISPLAY 2.276596 (-2300 1725);
PAINT GREEN (-2300 1725);
DISPLAY INVISIBLE (-2300 1725);
FORCEPROP 1 LAST HDL_TAP TRUE
J 0
(-2030 1595);
DISPLAY 2.276596 (-2030 1595);
PAINT GREEN (-2030 1595);
DISPLAY INVISIBLE (-2030 1595);
FORCEPROP 1 LAST PATH I156
J 0
(-2352 1725);
DISPLAY 0.872340 (-2352 1725);
PAINT GREEN (-2352 1725);
DISPLAY INVISIBLE (-2352 1725);
FORCEADD TAP..7
(-2550 1725);
FORCEPROP 3 LASTPIN (-2550 1775) SIG_NAME P3E_CPU0_PE1_PCH_C_TXN<14>
J 0
(-2540 1785);
DISPLAY 0.659574 (-2540 1785);
PAINT MONO (-2540 1785);
DISPLAY INVISIBLE (-2540 1785);
FORCEPROP 1 LASTPIN (-2550 1775) BN 14
R 1
J 0
(-2557 1723);
DISPLAY 0.617021 (-2557 1723);
PAINT GREEN (-2557 1723);
FORCEPROP 2 LAST CDS_LIB mstr_standard
J 0
(-2550 1725);
PAINT ORANGE (-2550 1725);
DISPLAY INVISIBLE (-2550 1725);
FORCEPROP 1 LAST BODY_TYPE PLUMBING
J 0
(-2500 1725);
DISPLAY 2.276596 (-2500 1725);
PAINT GREEN (-2500 1725);
DISPLAY INVISIBLE (-2500 1725);
FORCEPROP 1 LAST HDL_TAP TRUE
J 0
(-2230 1595);
DISPLAY 2.276596 (-2230 1595);
PAINT GREEN (-2230 1595);
DISPLAY INVISIBLE (-2230 1595);
FORCEPROP 1 LAST PATH I157
J 0
(-2552 1725);
DISPLAY 0.872340 (-2552 1725);
PAINT GREEN (-2552 1725);
DISPLAY INVISIBLE (-2552 1725);
FORCEADD TAP..7
(-2750 1725);
FORCEPROP 3 LASTPIN (-2750 1775) SIG_NAME P3E_CPU0_PE1_PCH_C_TXN<15>
J 0
(-2740 1785);
DISPLAY 0.659574 (-2740 1785);
PAINT MONO (-2740 1785);
DISPLAY INVISIBLE (-2740 1785);
FORCEPROP 1 LASTPIN (-2750 1775) BN 15
R 1
J 0
(-2757 1723);
DISPLAY 0.617021 (-2757 1723);
PAINT GREEN (-2757 1723);
FORCEPROP 2 LAST CDS_LIB mstr_standard
J 0
(-2750 1725);
PAINT ORANGE (-2750 1725);
DISPLAY INVISIBLE (-2750 1725);
FORCEPROP 1 LAST BODY_TYPE PLUMBING
J 0
(-2700 1725);
DISPLAY 2.276596 (-2700 1725);
PAINT GREEN (-2700 1725);
DISPLAY INVISIBLE (-2700 1725);
FORCEPROP 1 LAST HDL_TAP TRUE
J 0
(-2430 1595);
DISPLAY 2.276596 (-2430 1595);
PAINT GREEN (-2430 1595);
DISPLAY INVISIBLE (-2430 1595);
FORCEPROP 1 LAST PATH I158
J 0
(-2752 1725);
DISPLAY 0.872340 (-2752 1725);
PAINT GREEN (-2752 1725);
DISPLAY INVISIBLE (-2752 1725);
FORCEADD TAP..3
(-1350 2525);
FORCEPROP 3 LASTPIN (-1350 2475) SIG_NAME P3E_CPU0_PE1_PCH_TXN<8>
J 0
(-1340 2485);
DISPLAY 0.659574 (-1340 2485);
PAINT MONO (-1340 2485);
DISPLAY INVISIBLE (-1340 2485);
FORCEPROP 1 LASTPIN (-1350 2475) BN 8
R 1
J 0
(-1357 2463);
DISPLAY 0.617021 (-1357 2463);
PAINT GREEN (-1357 2463);
FORCEPROP 2 LAST CDS_LIB mstr_standard
J 0
(-1350 2525);
PAINT ORANGE (-1350 2525);
DISPLAY INVISIBLE (-1350 2525);
FORCEPROP 1 LAST BODY_TYPE PLUMBING
J 0
(-1300 2475);
DISPLAY 2.276596 (-1300 2475);
PAINT GREEN (-1300 2475);
DISPLAY INVISIBLE (-1300 2475);
FORCEPROP 1 LAST HDL_TAP TRUE
J 0
(-1030 2395);
DISPLAY 2.276596 (-1030 2395);
PAINT GREEN (-1030 2395);
DISPLAY INVISIBLE (-1030 2395);
FORCEPROP 1 LAST PATH I159
J 0
(-1352 2525);
DISPLAY 0.872340 (-1352 2525);
PAINT GREEN (-1352 2525);
DISPLAY INVISIBLE (-1352 2525);
FORCEADD TAP..3
(-500 3900);
FORCEPROP 3 LASTPIN (-500 3850) SIG_NAME P3E_CPU0_PE2_SS_TXN<14>
J 0
(-490 3860);
DISPLAY 0.659574 (-490 3860);
PAINT MONO (-490 3860);
DISPLAY INVISIBLE (-490 3860);
FORCEPROP 1 LASTPIN (-500 3850) BN 14
R 1
J 0
(-507 3838);
DISPLAY 0.617021 (-507 3838);
PAINT GREEN (-507 3838);
FORCEPROP 2 LAST CDS_LIB mstr_standard
J 0
(-500 3900);
PAINT ORANGE (-500 3900);
DISPLAY INVISIBLE (-500 3900);
FORCEPROP 1 LAST BODY_TYPE PLUMBING
J 0
(-450 3850);
DISPLAY 2.276596 (-450 3850);
PAINT GREEN (-450 3850);
DISPLAY INVISIBLE (-450 3850);
FORCEPROP 1 LAST HDL_TAP TRUE
J 0
(-180 3770);
DISPLAY 2.276596 (-180 3770);
PAINT GREEN (-180 3770);
DISPLAY INVISIBLE (-180 3770);
FORCEPROP 1 LAST PATH I16
J 0
(-502 3900);
DISPLAY 0.872340 (-502 3900);
PAINT GREEN (-502 3900);
DISPLAY INVISIBLE (-502 3900);
FORCEADD CAP..1
R 2
(-1350 2275);
FORCEPROP 1 LAST LOCATION C6B19
J 2
(-1400 2375);
DISPLAY 0.617021 (-1400 2375);
PAINT AQUA (-1400 2375);
FORCEPROP 1 LAST PART_NUMBER A36096-155
J 2
(-1400 2125);
DISPLAY 0.617021 (-1400 2125);
PAINT BLUE (-1400 2125);
FORCEPROP 1 LAST VALUE 0.22UF
J 2
(-1400 2325);
DISPLAY 0.617021 (-1400 2325);
PAINT SKYBLUE (-1400 2325);
FORCEPROP 1 LAST TOLERANCE 10%
J 2
(-1400 2225);
DISPLAY 0.617021 (-1400 2225);
PAINT SKYBLUE (-1400 2225);
FORCEPROP 1 LAST PACK_TYPE 0402
J 2
(-1400 2075);
DISPLAY 0.617021 (-1400 2075);
PAINT SKYBLUE (-1400 2075);
FORCEPROP 1 LAST VOLTAGE 16V
J 2
(-1400 2275);
DISPLAY 0.617021 (-1400 2275);
PAINT SKYBLUE (-1400 2275);
FORCEPROP 1 LAST MATERIAL X7R
J 2
(-1400 2175);
DISPLAY 0.617021 (-1400 2175);
PAINT SKYBLUE (-1400 2175);
FORCEPROP 1 LASTPIN (-1350 2175) $PN 2
J 2
(-1360 2155);
DISPLAY 0.617021 (-1360 2155);
PAINT ORANGE (-1360 2155);
FORCEPROP 1 LASTPIN (-1350 2375) $PN 1
J 2
(-1360 2355);
DISPLAY 0.617021 (-1360 2355);
PAINT ORANGE (-1360 2355);
FORCEPROP 2 LAST SEC_TYPE 0402
J 0
(-1400 2475);
DISPLAY 1.021277 (-1400 2475);
PAINT ORANGE (-1400 2475);
DISPLAY INVISIBLE (-1400 2475);
FORCEPROP 2 LAST CDS_LIB mstr_discrete
J 0
(-1350 2275);
PAINT ORANGE (-1350 2275);
DISPLAY INVISIBLE (-1350 2275);
FORCEPROP 2 LAST SEC 1
J 0
(-1400 2475);
DISPLAY 0.680851 (-1400 2475);
PAINT MONO (-1400 2475);
DISPLAY INVISIBLE (-1400 2475);
FORCEPROP 2 LAST CDS_LOCATION C6B19
J 2
(-1400 2375);
DISPLAY 0.617021 (-1400 2375);
PAINT AQUA (-1400 2375);
DISPLAY INVISIBLE (-1400 2375);
FORCEPROP 1 LAST PATH I160
J 2
(-1400 2425);
DISPLAY 0.978723 (-1400 2425);
PAINT WHITE (-1400 2425);
DISPLAY INVISIBLE (-1400 2425);
FORCEPROP 2 LAST ROOM OCP_STEERING
J 2
(-1350 2275);
PAINT MONO (-1350 2275);
DISPLAY INVISIBLE (-1350 2275);
FORCEADD TAP..3
(-1550 2525);
FORCEPROP 3 LASTPIN (-1550 2475) SIG_NAME P3E_CPU0_PE1_PCH_TXN<9>
J 0
(-1540 2485);
DISPLAY 0.659574 (-1540 2485);
PAINT MONO (-1540 2485);
DISPLAY INVISIBLE (-1540 2485);
FORCEPROP 1 LASTPIN (-1550 2475) BN 9
R 1
J 0
(-1557 2463);
DISPLAY 0.617021 (-1557 2463);
PAINT GREEN (-1557 2463);
FORCEPROP 2 LAST CDS_LIB mstr_standard
J 0
(-1550 2525);
PAINT ORANGE (-1550 2525);
DISPLAY INVISIBLE (-1550 2525);
FORCEPROP 1 LAST BODY_TYPE PLUMBING
J 0
(-1500 2475);
DISPLAY 2.276596 (-1500 2475);
PAINT GREEN (-1500 2475);
DISPLAY INVISIBLE (-1500 2475);
FORCEPROP 1 LAST HDL_TAP TRUE
J 0
(-1230 2395);
DISPLAY 2.276596 (-1230 2395);
PAINT GREEN (-1230 2395);
DISPLAY INVISIBLE (-1230 2395);
FORCEPROP 1 LAST PATH I161
J 0
(-1552 2525);
DISPLAY 0.872340 (-1552 2525);
PAINT GREEN (-1552 2525);
DISPLAY INVISIBLE (-1552 2525);
FORCEADD TAP..3
(-1750 2525);
FORCEPROP 3 LASTPIN (-1750 2475) SIG_NAME P3E_CPU0_PE1_PCH_TXN<10>
J 0
(-1740 2485);
DISPLAY 0.659574 (-1740 2485);
PAINT MONO (-1740 2485);
DISPLAY INVISIBLE (-1740 2485);
FORCEPROP 1 LASTPIN (-1750 2475) BN 10
R 1
J 0
(-1757 2463);
DISPLAY 0.617021 (-1757 2463);
PAINT GREEN (-1757 2463);
FORCEPROP 2 LAST CDS_LIB mstr_standard
J 0
(-1750 2525);
PAINT ORANGE (-1750 2525);
DISPLAY INVISIBLE (-1750 2525);
FORCEPROP 1 LAST BODY_TYPE PLUMBING
J 0
(-1700 2475);
DISPLAY 2.276596 (-1700 2475);
PAINT GREEN (-1700 2475);
DISPLAY INVISIBLE (-1700 2475);
FORCEPROP 1 LAST HDL_TAP TRUE
J 0
(-1430 2395);
DISPLAY 2.276596 (-1430 2395);
PAINT GREEN (-1430 2395);
DISPLAY INVISIBLE (-1430 2395);
FORCEPROP 1 LAST PATH I162
J 0
(-1752 2525);
DISPLAY 0.872340 (-1752 2525);
PAINT GREEN (-1752 2525);
DISPLAY INVISIBLE (-1752 2525);
FORCEADD CAP..1
R 2
(-1750 2275);
FORCEPROP 1 LAST LOCATION C6B15
J 2
(-1800 2375);
DISPLAY 0.617021 (-1800 2375);
PAINT AQUA (-1800 2375);
FORCEPROP 1 LAST PART_NUMBER A36096-155
J 2
(-1800 2125);
DISPLAY 0.617021 (-1800 2125);
PAINT BLUE (-1800 2125);
FORCEPROP 1 LAST VALUE 0.22UF
J 2
(-1800 2325);
DISPLAY 0.617021 (-1800 2325);
PAINT SKYBLUE (-1800 2325);
FORCEPROP 1 LAST TOLERANCE 10%
J 2
(-1800 2225);
DISPLAY 0.617021 (-1800 2225);
PAINT SKYBLUE (-1800 2225);
FORCEPROP 1 LAST PACK_TYPE 0402
J 2
(-1800 2075);
DISPLAY 0.617021 (-1800 2075);
PAINT SKYBLUE (-1800 2075);
FORCEPROP 1 LAST VOLTAGE 16V
J 2
(-1800 2275);
DISPLAY 0.617021 (-1800 2275);
PAINT SKYBLUE (-1800 2275);
FORCEPROP 1 LAST MATERIAL X7R
J 2
(-1800 2175);
DISPLAY 0.617021 (-1800 2175);
PAINT SKYBLUE (-1800 2175);
FORCEPROP 1 LASTPIN (-1750 2175) $PN 2
J 2
(-1760 2155);
DISPLAY 0.617021 (-1760 2155);
PAINT ORANGE (-1760 2155);
FORCEPROP 1 LASTPIN (-1750 2375) $PN 1
J 2
(-1760 2355);
DISPLAY 0.617021 (-1760 2355);
PAINT ORANGE (-1760 2355);
FORCEPROP 2 LAST SEC_TYPE 0402
J 0
(-1800 2475);
DISPLAY 1.021277 (-1800 2475);
PAINT ORANGE (-1800 2475);
DISPLAY INVISIBLE (-1800 2475);
FORCEPROP 2 LAST CDS_LIB mstr_discrete
J 0
(-1750 2275);
PAINT ORANGE (-1750 2275);
DISPLAY INVISIBLE (-1750 2275);
FORCEPROP 2 LAST SEC 1
J 0
(-1800 2475);
DISPLAY 0.680851 (-1800 2475);
PAINT MONO (-1800 2475);
DISPLAY INVISIBLE (-1800 2475);
FORCEPROP 2 LAST CDS_LOCATION C6B15
J 2
(-1800 2375);
DISPLAY 0.617021 (-1800 2375);
PAINT AQUA (-1800 2375);
DISPLAY INVISIBLE (-1800 2375);
FORCEPROP 1 LAST PATH I163
J 2
(-1800 2425);
DISPLAY 0.978723 (-1800 2425);
PAINT WHITE (-1800 2425);
DISPLAY INVISIBLE (-1800 2425);
FORCEPROP 2 LAST ROOM OCP_STEERING
J 2
(-1750 2275);
PAINT MONO (-1750 2275);
DISPLAY INVISIBLE (-1750 2275);
FORCEADD TAP..3
(-2150 2525);
FORCEPROP 3 LASTPIN (-2150 2475) SIG_NAME P3E_CPU0_PE1_PCH_TXN<12>
J 0
(-2140 2485);
DISPLAY 0.659574 (-2140 2485);
PAINT MONO (-2140 2485);
DISPLAY INVISIBLE (-2140 2485);
FORCEPROP 1 LASTPIN (-2150 2475) BN 12
R 1
J 0
(-2157 2463);
DISPLAY 0.617021 (-2157 2463);
PAINT GREEN (-2157 2463);
FORCEPROP 2 LAST CDS_LIB mstr_standard
J 0
(-2150 2525);
PAINT ORANGE (-2150 2525);
DISPLAY INVISIBLE (-2150 2525);
FORCEPROP 1 LAST BODY_TYPE PLUMBING
J 0
(-2100 2475);
DISPLAY 2.276596 (-2100 2475);
PAINT GREEN (-2100 2475);
DISPLAY INVISIBLE (-2100 2475);
FORCEPROP 1 LAST HDL_TAP TRUE
J 0
(-1830 2395);
DISPLAY 2.276596 (-1830 2395);
PAINT GREEN (-1830 2395);
DISPLAY INVISIBLE (-1830 2395);
FORCEPROP 1 LAST PATH I164
J 0
(-2152 2525);
DISPLAY 0.872340 (-2152 2525);
PAINT GREEN (-2152 2525);
DISPLAY INVISIBLE (-2152 2525);
FORCEADD TAP..3
(-1950 2525);
FORCEPROP 3 LASTPIN (-1950 2475) SIG_NAME P3E_CPU0_PE1_PCH_TXN<11>
J 0
(-1940 2485);
DISPLAY 0.659574 (-1940 2485);
PAINT MONO (-1940 2485);
DISPLAY INVISIBLE (-1940 2485);
FORCEPROP 1 LASTPIN (-1950 2475) BN 11
R 1
J 0
(-1957 2463);
DISPLAY 0.617021 (-1957 2463);
PAINT GREEN (-1957 2463);
FORCEPROP 2 LAST CDS_LIB mstr_standard
J 0
(-1950 2525);
PAINT ORANGE (-1950 2525);
DISPLAY INVISIBLE (-1950 2525);
FORCEPROP 1 LAST BODY_TYPE PLUMBING
J 0
(-1900 2475);
DISPLAY 2.276596 (-1900 2475);
PAINT GREEN (-1900 2475);
DISPLAY INVISIBLE (-1900 2475);
FORCEPROP 1 LAST HDL_TAP TRUE
J 0
(-1630 2395);
DISPLAY 2.276596 (-1630 2395);
PAINT GREEN (-1630 2395);
DISPLAY INVISIBLE (-1630 2395);
FORCEPROP 1 LAST PATH I165
J 0
(-1952 2525);
DISPLAY 0.872340 (-1952 2525);
PAINT GREEN (-1952 2525);
DISPLAY INVISIBLE (-1952 2525);
FORCEADD CAP..1
R 2
(-2150 2275);
FORCEPROP 1 LAST LOCATION C6B11
J 2
(-2200 2375);
DISPLAY 0.617021 (-2200 2375);
PAINT AQUA (-2200 2375);
FORCEPROP 1 LAST PART_NUMBER A36096-155
J 2
(-2200 2125);
DISPLAY 0.617021 (-2200 2125);
PAINT BLUE (-2200 2125);
FORCEPROP 1 LAST VALUE 0.22UF
J 2
(-2200 2325);
DISPLAY 0.617021 (-2200 2325);
PAINT SKYBLUE (-2200 2325);
FORCEPROP 1 LAST TOLERANCE 10%
J 2
(-2200 2225);
DISPLAY 0.617021 (-2200 2225);
PAINT SKYBLUE (-2200 2225);
FORCEPROP 1 LAST PACK_TYPE 0402
J 2
(-2200 2075);
DISPLAY 0.617021 (-2200 2075);
PAINT SKYBLUE (-2200 2075);
FORCEPROP 1 LAST VOLTAGE 16V
J 2
(-2200 2275);
DISPLAY 0.617021 (-2200 2275);
PAINT SKYBLUE (-2200 2275);
FORCEPROP 1 LAST MATERIAL X7R
J 2
(-2200 2175);
DISPLAY 0.617021 (-2200 2175);
PAINT SKYBLUE (-2200 2175);
FORCEPROP 1 LASTPIN (-2150 2175) $PN 2
J 2
(-2160 2155);
DISPLAY 0.617021 (-2160 2155);
PAINT ORANGE (-2160 2155);
FORCEPROP 1 LASTPIN (-2150 2375) $PN 1
J 2
(-2160 2355);
DISPLAY 0.617021 (-2160 2355);
PAINT ORANGE (-2160 2355);
FORCEPROP 2 LAST SEC_TYPE 0402
J 0
(-2200 2475);
DISPLAY 1.021277 (-2200 2475);
PAINT ORANGE (-2200 2475);
DISPLAY INVISIBLE (-2200 2475);
FORCEPROP 2 LAST CDS_LIB mstr_discrete
J 0
(-2150 2275);
PAINT ORANGE (-2150 2275);
DISPLAY INVISIBLE (-2150 2275);
FORCEPROP 2 LAST SEC 1
J 0
(-2200 2475);
DISPLAY 0.680851 (-2200 2475);
PAINT MONO (-2200 2475);
DISPLAY INVISIBLE (-2200 2475);
FORCEPROP 2 LAST CDS_LOCATION C6B11
J 2
(-2200 2375);
DISPLAY 0.617021 (-2200 2375);
PAINT AQUA (-2200 2375);
DISPLAY INVISIBLE (-2200 2375);
FORCEPROP 1 LAST PATH I166
J 2
(-2200 2425);
DISPLAY 0.978723 (-2200 2425);
PAINT WHITE (-2200 2425);
DISPLAY INVISIBLE (-2200 2425);
FORCEPROP 2 LAST ROOM OCP_STEERING
J 2
(-2150 2275);
PAINT MONO (-2150 2275);
DISPLAY INVISIBLE (-2150 2275);
FORCEADD TAP..3
(-2350 2525);
FORCEPROP 3 LASTPIN (-2350 2475) SIG_NAME P3E_CPU0_PE1_PCH_TXN<13>
J 0
(-2340 2485);
DISPLAY 0.659574 (-2340 2485);
PAINT MONO (-2340 2485);
DISPLAY INVISIBLE (-2340 2485);
FORCEPROP 1 LASTPIN (-2350 2475) BN 13
R 1
J 0
(-2357 2463);
DISPLAY 0.617021 (-2357 2463);
PAINT GREEN (-2357 2463);
FORCEPROP 2 LAST CDS_LIB mstr_standard
J 0
(-2350 2525);
PAINT ORANGE (-2350 2525);
DISPLAY INVISIBLE (-2350 2525);
FORCEPROP 1 LAST BODY_TYPE PLUMBING
J 0
(-2300 2475);
DISPLAY 2.276596 (-2300 2475);
PAINT GREEN (-2300 2475);
DISPLAY INVISIBLE (-2300 2475);
FORCEPROP 1 LAST HDL_TAP TRUE
J 0
(-2030 2395);
DISPLAY 2.276596 (-2030 2395);
PAINT GREEN (-2030 2395);
DISPLAY INVISIBLE (-2030 2395);
FORCEPROP 1 LAST PATH I167
J 0
(-2352 2525);
DISPLAY 0.872340 (-2352 2525);
PAINT GREEN (-2352 2525);
DISPLAY INVISIBLE (-2352 2525);
FORCEADD TAP..3
(-2550 2525);
FORCEPROP 3 LASTPIN (-2550 2475) SIG_NAME P3E_CPU0_PE1_PCH_TXN<14>
J 0
(-2540 2485);
DISPLAY 0.659574 (-2540 2485);
PAINT MONO (-2540 2485);
DISPLAY INVISIBLE (-2540 2485);
FORCEPROP 1 LASTPIN (-2550 2475) BN 14
R 1
J 0
(-2557 2463);
DISPLAY 0.617021 (-2557 2463);
PAINT GREEN (-2557 2463);
FORCEPROP 2 LAST CDS_LIB mstr_standard
J 0
(-2550 2525);
PAINT ORANGE (-2550 2525);
DISPLAY INVISIBLE (-2550 2525);
FORCEPROP 1 LAST BODY_TYPE PLUMBING
J 0
(-2500 2475);
DISPLAY 2.276596 (-2500 2475);
PAINT GREEN (-2500 2475);
DISPLAY INVISIBLE (-2500 2475);
FORCEPROP 1 LAST HDL_TAP TRUE
J 0
(-2230 2395);
DISPLAY 2.276596 (-2230 2395);
PAINT GREEN (-2230 2395);
DISPLAY INVISIBLE (-2230 2395);
FORCEPROP 1 LAST PATH I168
J 0
(-2552 2525);
DISPLAY 0.872340 (-2552 2525);
PAINT GREEN (-2552 2525);
DISPLAY INVISIBLE (-2552 2525);
FORCEADD CAP..1
R 2
(-2550 2275);
FORCEPROP 1 LAST LOCATION C6B6
J 2
(-2600 2375);
DISPLAY 0.617021 (-2600 2375);
PAINT AQUA (-2600 2375);
FORCEPROP 1 LAST PART_NUMBER A36096-155
J 2
(-2600 2125);
DISPLAY 0.617021 (-2600 2125);
PAINT BLUE (-2600 2125);
FORCEPROP 1 LAST VALUE 0.22UF
J 2
(-2600 2325);
DISPLAY 0.617021 (-2600 2325);
PAINT SKYBLUE (-2600 2325);
FORCEPROP 1 LAST TOLERANCE 10%
J 2
(-2600 2225);
DISPLAY 0.617021 (-2600 2225);
PAINT SKYBLUE (-2600 2225);
FORCEPROP 1 LAST PACK_TYPE 0402
J 2
(-2600 2075);
DISPLAY 0.617021 (-2600 2075);
PAINT SKYBLUE (-2600 2075);
FORCEPROP 1 LAST VOLTAGE 16V
J 2
(-2600 2275);
DISPLAY 0.617021 (-2600 2275);
PAINT SKYBLUE (-2600 2275);
FORCEPROP 1 LAST MATERIAL X7R
J 2
(-2600 2175);
DISPLAY 0.617021 (-2600 2175);
PAINT SKYBLUE (-2600 2175);
FORCEPROP 1 LASTPIN (-2550 2175) $PN 2
J 2
(-2560 2155);
DISPLAY 0.617021 (-2560 2155);
PAINT ORANGE (-2560 2155);
FORCEPROP 1 LASTPIN (-2550 2375) $PN 1
J 2
(-2560 2355);
DISPLAY 0.617021 (-2560 2355);
PAINT ORANGE (-2560 2355);
FORCEPROP 2 LAST SEC_TYPE 0402
J 0
(-2600 2475);
DISPLAY 1.021277 (-2600 2475);
PAINT ORANGE (-2600 2475);
DISPLAY INVISIBLE (-2600 2475);
FORCEPROP 2 LAST CDS_LIB mstr_discrete
J 0
(-2550 2275);
PAINT ORANGE (-2550 2275);
DISPLAY INVISIBLE (-2550 2275);
FORCEPROP 2 LAST SEC 1
J 0
(-2600 2475);
DISPLAY 0.680851 (-2600 2475);
PAINT MONO (-2600 2475);
DISPLAY INVISIBLE (-2600 2475);
FORCEPROP 2 LAST CDS_LOCATION C6B6
J 2
(-2600 2375);
DISPLAY 0.617021 (-2600 2375);
PAINT AQUA (-2600 2375);
DISPLAY INVISIBLE (-2600 2375);
FORCEPROP 1 LAST PATH I169
J 2
(-2600 2425);
DISPLAY 0.978723 (-2600 2425);
PAINT WHITE (-2600 2425);
DISPLAY INVISIBLE (-2600 2425);
FORCEPROP 2 LAST ROOM OCP_STEERING
J 2
(-2550 2275);
PAINT MONO (-2550 2275);
DISPLAY INVISIBLE (-2550 2275);
FORCEADD TAP..7
(-550 4100);
FORCEPROP 3 LASTPIN (-550 4150) SIG_NAME P3E_CPU0_PE2_SS_C_TXP<14>
J 0
(-540 4160);
DISPLAY 0.659574 (-540 4160);
PAINT MONO (-540 4160);
DISPLAY INVISIBLE (-540 4160);
FORCEPROP 1 LASTPIN (-550 4150) BN 14
R 1
J 0
(-557 4098);
DISPLAY 0.617021 (-557 4098);
PAINT GREEN (-557 4098);
FORCEPROP 2 LAST CDS_LIB mstr_standard
J 0
(-550 4100);
PAINT ORANGE (-550 4100);
DISPLAY INVISIBLE (-550 4100);
FORCEPROP 1 LAST BODY_TYPE PLUMBING
J 0
(-500 4100);
DISPLAY 2.276596 (-500 4100);
PAINT GREEN (-500 4100);
DISPLAY INVISIBLE (-500 4100);
FORCEPROP 1 LAST HDL_TAP TRUE
J 0
(-230 3970);
DISPLAY 2.276596 (-230 3970);
PAINT GREEN (-230 3970);
DISPLAY INVISIBLE (-230 3970);
FORCEPROP 1 LAST PATH I17
J 0
(-552 4100);
DISPLAY 0.872340 (-552 4100);
PAINT GREEN (-552 4100);
DISPLAY INVISIBLE (-552 4100);
FORCEADD TAP..3
(-2750 2525);
FORCEPROP 3 LASTPIN (-2750 2475) SIG_NAME P3E_CPU0_PE1_PCH_TXN<15>
J 0
(-2740 2485);
DISPLAY 0.659574 (-2740 2485);
PAINT MONO (-2740 2485);
DISPLAY INVISIBLE (-2740 2485);
FORCEPROP 1 LASTPIN (-2750 2475) BN 15
R 1
J 0
(-2757 2463);
DISPLAY 0.617021 (-2757 2463);
PAINT GREEN (-2757 2463);
FORCEPROP 2 LAST CDS_LIB mstr_standard
J 0
(-2750 2525);
PAINT ORANGE (-2750 2525);
DISPLAY INVISIBLE (-2750 2525);
FORCEPROP 1 LAST BODY_TYPE PLUMBING
J 0
(-2700 2475);
DISPLAY 2.276596 (-2700 2475);
PAINT GREEN (-2700 2475);
DISPLAY INVISIBLE (-2700 2475);
FORCEPROP 1 LAST HDL_TAP TRUE
J 0
(-2430 2395);
DISPLAY 2.276596 (-2430 2395);
PAINT GREEN (-2430 2395);
DISPLAY INVISIBLE (-2430 2395);
FORCEPROP 1 LAST PATH I170
J 0
(-2752 2525);
DISPLAY 0.872340 (-2752 2525);
PAINT GREEN (-2752 2525);
DISPLAY INVISIBLE (-2752 2525);
FORCEADD OFFPAGE..1
(-2925 2575);
FORCEPROP 2 LAST $XR0 30 
J 0
(-3176 2575);
DISPLAY 0.638298 (-3176 2575);
PAINT MONO (-3176 2575);
FORCEPROP 2 LAST $XR1 244 
J 0
(-3176 2575);
DISPLAY 0.638298 (-3176 2575);
PAINT MONO (-3176 2575);
FORCEPROP 2 LAST CDS_LIB mstr_standard
J 0
(-2925 2575);
PAINT ORANGE (-2925 2575);
DISPLAY INVISIBLE (-2925 2575);
FORCEPROP 1 LAST OFFPAGE TRUE
J 0
(-2605 2445);
PAINT GREEN (-2605 2445);
DISPLAY INVISIBLE (-2605 2445);
FORCEPROP 1 LAST COMMENT_BODY TRUE
J 0
(-2805 2475);
DISPLAY 2.276596 (-2805 2475);
PAINT GREEN (-2805 2475);
DISPLAY INVISIBLE (-2805 2475);
FORCEPROP 2 LAST PATH I171
J 0
(-2875 2650);
DISPLAY 1.021277 (-2875 2650);
PAINT ORANGE (-2875 2650);
DISPLAY INVISIBLE (-2875 2650);
FORCEADD TAP..3
(-1300 1525);
FORCEPROP 3 LASTPIN (-1300 1475) SIG_NAME P3E_CPU0_PE1_PCH_TXP<8>
J 0
(-1290 1485);
DISPLAY 0.659574 (-1290 1485);
PAINT MONO (-1290 1485);
DISPLAY INVISIBLE (-1290 1485);
FORCEPROP 1 LASTPIN (-1300 1475) BN 8
R 1
J 0
(-1307 1463);
DISPLAY 0.617021 (-1307 1463);
PAINT GREEN (-1307 1463);
FORCEPROP 2 LAST CDS_LIB mstr_standard
J 0
(-1300 1525);
PAINT ORANGE (-1300 1525);
DISPLAY INVISIBLE (-1300 1525);
FORCEPROP 1 LAST BODY_TYPE PLUMBING
J 0
(-1250 1475);
DISPLAY 2.276596 (-1250 1475);
PAINT GREEN (-1250 1475);
DISPLAY INVISIBLE (-1250 1475);
FORCEPROP 1 LAST HDL_TAP TRUE
J 0
(-980 1395);
DISPLAY 2.276596 (-980 1395);
PAINT GREEN (-980 1395);
DISPLAY INVISIBLE (-980 1395);
FORCEPROP 1 LAST PATH I172
J 0
(-1302 1525);
DISPLAY 0.872340 (-1302 1525);
PAINT GREEN (-1302 1525);
DISPLAY INVISIBLE (-1302 1525);
FORCEADD CAP..1
R 2
(-1300 1275);
FORCEPROP 1 LAST LOCATION C6B20
J 2
(-1350 1375);
DISPLAY 0.617021 (-1350 1375);
PAINT AQUA (-1350 1375);
FORCEPROP 1 LAST PART_NUMBER A36096-155
J 2
(-1350 1125);
DISPLAY 0.617021 (-1350 1125);
PAINT BLUE (-1350 1125);
FORCEPROP 1 LAST VALUE 0.22UF
J 2
(-1350 1325);
DISPLAY 0.617021 (-1350 1325);
PAINT SKYBLUE (-1350 1325);
FORCEPROP 1 LAST TOLERANCE 10%
J 2
(-1350 1225);
DISPLAY 0.617021 (-1350 1225);
PAINT SKYBLUE (-1350 1225);
FORCEPROP 1 LAST PACK_TYPE 0402
J 2
(-1350 1075);
DISPLAY 0.617021 (-1350 1075);
PAINT SKYBLUE (-1350 1075);
FORCEPROP 1 LAST VOLTAGE 16V
J 2
(-1350 1275);
DISPLAY 0.617021 (-1350 1275);
PAINT SKYBLUE (-1350 1275);
FORCEPROP 1 LAST MATERIAL X7R
J 2
(-1350 1175);
DISPLAY 0.617021 (-1350 1175);
PAINT SKYBLUE (-1350 1175);
FORCEPROP 1 LASTPIN (-1300 1175) $PN 2
J 2
(-1310 1155);
DISPLAY 0.617021 (-1310 1155);
PAINT ORANGE (-1310 1155);
FORCEPROP 1 LASTPIN (-1300 1375) $PN 1
J 2
(-1310 1355);
DISPLAY 0.617021 (-1310 1355);
PAINT ORANGE (-1310 1355);
FORCEPROP 2 LAST SEC_TYPE 0402
J 0
(-1350 1475);
DISPLAY 1.021277 (-1350 1475);
PAINT ORANGE (-1350 1475);
DISPLAY INVISIBLE (-1350 1475);
FORCEPROP 2 LAST CDS_LIB mstr_discrete
J 0
(-1300 1275);
PAINT ORANGE (-1300 1275);
DISPLAY INVISIBLE (-1300 1275);
FORCEPROP 2 LAST SEC 1
J 0
(-1350 1475);
DISPLAY 0.680851 (-1350 1475);
PAINT MONO (-1350 1475);
DISPLAY INVISIBLE (-1350 1475);
FORCEPROP 2 LAST CDS_LOCATION C6B20
J 2
(-1350 1375);
DISPLAY 0.617021 (-1350 1375);
PAINT AQUA (-1350 1375);
DISPLAY INVISIBLE (-1350 1375);
FORCEPROP 1 LAST PATH I173
J 2
(-1350 1425);
DISPLAY 0.978723 (-1350 1425);
PAINT WHITE (-1350 1425);
DISPLAY INVISIBLE (-1350 1425);
FORCEPROP 2 LAST ROOM OCP_STEERING
J 2
(-1300 1275);
PAINT MONO (-1300 1275);
DISPLAY INVISIBLE (-1300 1275);
FORCEADD TAP..7
(-1300 725);
FORCEPROP 3 LASTPIN (-1300 775) SIG_NAME P3E_CPU0_PE1_PCH_C_TXP<8>
J 0
(-1290 785);
DISPLAY 0.659574 (-1290 785);
PAINT MONO (-1290 785);
DISPLAY INVISIBLE (-1290 785);
FORCEPROP 1 LASTPIN (-1300 775) BN 8
R 1
J 0
(-1307 723);
DISPLAY 0.617021 (-1307 723);
PAINT GREEN (-1307 723);
FORCEPROP 2 LAST CDS_LIB mstr_standard
J 0
(-1300 725);
PAINT ORANGE (-1300 725);
DISPLAY INVISIBLE (-1300 725);
FORCEPROP 1 LAST BODY_TYPE PLUMBING
J 0
(-1250 725);
DISPLAY 2.276596 (-1250 725);
PAINT GREEN (-1250 725);
DISPLAY INVISIBLE (-1250 725);
FORCEPROP 1 LAST HDL_TAP TRUE
J 0
(-980 595);
DISPLAY 2.276596 (-980 595);
PAINT GREEN (-980 595);
DISPLAY INVISIBLE (-980 595);
FORCEPROP 1 LAST PATH I174
J 0
(-1302 725);
DISPLAY 0.872340 (-1302 725);
PAINT GREEN (-1302 725);
DISPLAY INVISIBLE (-1302 725);
FORCEADD CAP..1
R 2
(-1550 1975);
FORCEPROP 1 LAST LOCATION C6B17
J 2
(-1600 2075);
DISPLAY 0.617021 (-1600 2075);
PAINT AQUA (-1600 2075);
FORCEPROP 1 LAST PART_NUMBER A36096-155
J 2
(-1600 1825);
DISPLAY 0.617021 (-1600 1825);
PAINT BLUE (-1600 1825);
FORCEPROP 1 LAST VALUE 0.22UF
J 2
(-1600 2025);
DISPLAY 0.617021 (-1600 2025);
PAINT SKYBLUE (-1600 2025);
FORCEPROP 1 LAST TOLERANCE 10%
J 2
(-1600 1925);
DISPLAY 0.617021 (-1600 1925);
PAINT SKYBLUE (-1600 1925);
FORCEPROP 1 LAST PACK_TYPE 0402
J 2
(-1600 1775);
DISPLAY 0.617021 (-1600 1775);
PAINT SKYBLUE (-1600 1775);
FORCEPROP 1 LAST VOLTAGE 16V
J 2
(-1600 1975);
DISPLAY 0.617021 (-1600 1975);
PAINT SKYBLUE (-1600 1975);
FORCEPROP 1 LAST MATERIAL X7R
J 2
(-1600 1875);
DISPLAY 0.617021 (-1600 1875);
PAINT SKYBLUE (-1600 1875);
FORCEPROP 1 LASTPIN (-1550 1875) $PN 2
J 2
(-1560 1855);
DISPLAY 0.617021 (-1560 1855);
PAINT ORANGE (-1560 1855);
FORCEPROP 1 LASTPIN (-1550 2075) $PN 1
J 2
(-1560 2055);
DISPLAY 0.617021 (-1560 2055);
PAINT ORANGE (-1560 2055);
FORCEPROP 2 LAST SEC_TYPE 0402
J 0
(-1600 2175);
DISPLAY 1.021277 (-1600 2175);
PAINT ORANGE (-1600 2175);
DISPLAY INVISIBLE (-1600 2175);
FORCEPROP 2 LAST CDS_LIB mstr_discrete
J 0
(-1550 1975);
PAINT ORANGE (-1550 1975);
DISPLAY INVISIBLE (-1550 1975);
FORCEPROP 2 LAST SEC 1
J 0
(-1600 2175);
DISPLAY 0.680851 (-1600 2175);
PAINT MONO (-1600 2175);
DISPLAY INVISIBLE (-1600 2175);
FORCEPROP 2 LAST CDS_LOCATION C6B17
J 2
(-1600 2075);
DISPLAY 0.617021 (-1600 2075);
PAINT AQUA (-1600 2075);
DISPLAY INVISIBLE (-1600 2075);
FORCEPROP 1 LAST PATH I175
J 2
(-1600 2125);
DISPLAY 0.978723 (-1600 2125);
PAINT WHITE (-1600 2125);
DISPLAY INVISIBLE (-1600 2125);
FORCEPROP 2 LAST ROOM OCP_STEERING
J 2
(-1550 1975);
PAINT MONO (-1550 1975);
DISPLAY INVISIBLE (-1550 1975);
FORCEADD TAP..3
(-1500 1525);
FORCEPROP 3 LASTPIN (-1500 1475) SIG_NAME P3E_CPU0_PE1_PCH_TXP<9>
J 0
(-1490 1485);
DISPLAY 0.659574 (-1490 1485);
PAINT MONO (-1490 1485);
DISPLAY INVISIBLE (-1490 1485);
FORCEPROP 1 LASTPIN (-1500 1475) BN 9
R 1
J 0
(-1507 1463);
DISPLAY 0.617021 (-1507 1463);
PAINT GREEN (-1507 1463);
FORCEPROP 2 LAST CDS_LIB mstr_standard
J 0
(-1500 1525);
PAINT ORANGE (-1500 1525);
DISPLAY INVISIBLE (-1500 1525);
FORCEPROP 1 LAST BODY_TYPE PLUMBING
J 0
(-1450 1475);
DISPLAY 2.276596 (-1450 1475);
PAINT GREEN (-1450 1475);
DISPLAY INVISIBLE (-1450 1475);
FORCEPROP 1 LAST HDL_TAP TRUE
J 0
(-1180 1395);
DISPLAY 2.276596 (-1180 1395);
PAINT GREEN (-1180 1395);
DISPLAY INVISIBLE (-1180 1395);
FORCEPROP 1 LAST PATH I176
J 0
(-1502 1525);
DISPLAY 0.872340 (-1502 1525);
PAINT GREEN (-1502 1525);
DISPLAY INVISIBLE (-1502 1525);
FORCEADD TAP..7
(-1550 1725);
FORCEPROP 3 LASTPIN (-1550 1775) SIG_NAME P3E_CPU0_PE1_PCH_C_TXN<9>
J 0
(-1540 1785);
DISPLAY 0.659574 (-1540 1785);
PAINT MONO (-1540 1785);
DISPLAY INVISIBLE (-1540 1785);
FORCEPROP 1 LASTPIN (-1550 1775) BN 9
R 1
J 0
(-1557 1723);
DISPLAY 0.617021 (-1557 1723);
PAINT GREEN (-1557 1723);
FORCEPROP 2 LAST CDS_LIB mstr_standard
J 0
(-1550 1725);
PAINT ORANGE (-1550 1725);
DISPLAY INVISIBLE (-1550 1725);
FORCEPROP 1 LAST BODY_TYPE PLUMBING
J 0
(-1500 1725);
DISPLAY 2.276596 (-1500 1725);
PAINT GREEN (-1500 1725);
DISPLAY INVISIBLE (-1500 1725);
FORCEPROP 1 LAST HDL_TAP TRUE
J 0
(-1230 1595);
DISPLAY 2.276596 (-1230 1595);
PAINT GREEN (-1230 1595);
DISPLAY INVISIBLE (-1230 1595);
FORCEPROP 1 LAST PATH I177
J 0
(-1552 1725);
DISPLAY 0.872340 (-1552 1725);
PAINT GREEN (-1552 1725);
DISPLAY INVISIBLE (-1552 1725);
FORCEADD TAP..7
(-1750 1725);
FORCEPROP 3 LASTPIN (-1750 1775) SIG_NAME P3E_CPU0_PE1_PCH_C_TXN<10>
J 0
(-1740 1785);
DISPLAY 0.659574 (-1740 1785);
PAINT MONO (-1740 1785);
DISPLAY INVISIBLE (-1740 1785);
FORCEPROP 1 LASTPIN (-1750 1775) BN 10
R 1
J 0
(-1757 1723);
DISPLAY 0.617021 (-1757 1723);
PAINT GREEN (-1757 1723);
FORCEPROP 2 LAST CDS_LIB mstr_standard
J 0
(-1750 1725);
PAINT ORANGE (-1750 1725);
DISPLAY INVISIBLE (-1750 1725);
FORCEPROP 1 LAST BODY_TYPE PLUMBING
J 0
(-1700 1725);
DISPLAY 2.276596 (-1700 1725);
PAINT GREEN (-1700 1725);
DISPLAY INVISIBLE (-1700 1725);
FORCEPROP 1 LAST HDL_TAP TRUE
J 0
(-1430 1595);
DISPLAY 2.276596 (-1430 1595);
PAINT GREEN (-1430 1595);
DISPLAY INVISIBLE (-1430 1595);
FORCEPROP 1 LAST PATH I178
J 0
(-1752 1725);
DISPLAY 0.872340 (-1752 1725);
PAINT GREEN (-1752 1725);
DISPLAY INVISIBLE (-1752 1725);
FORCEADD TAP..3
(-1700 1525);
FORCEPROP 3 LASTPIN (-1700 1475) SIG_NAME P3E_CPU0_PE1_PCH_TXP<10>
J 0
(-1690 1485);
DISPLAY 0.659574 (-1690 1485);
PAINT MONO (-1690 1485);
DISPLAY INVISIBLE (-1690 1485);
FORCEPROP 1 LASTPIN (-1700 1475) BN 10
R 1
J 0
(-1707 1463);
DISPLAY 0.617021 (-1707 1463);
PAINT GREEN (-1707 1463);
FORCEPROP 2 LAST CDS_LIB mstr_standard
J 0
(-1700 1525);
PAINT ORANGE (-1700 1525);
DISPLAY INVISIBLE (-1700 1525);
FORCEPROP 1 LAST BODY_TYPE PLUMBING
J 0
(-1650 1475);
DISPLAY 2.276596 (-1650 1475);
PAINT GREEN (-1650 1475);
DISPLAY INVISIBLE (-1650 1475);
FORCEPROP 1 LAST HDL_TAP TRUE
J 0
(-1380 1395);
DISPLAY 2.276596 (-1380 1395);
PAINT GREEN (-1380 1395);
DISPLAY INVISIBLE (-1380 1395);
FORCEPROP 1 LAST PATH I179
J 0
(-1702 1525);
DISPLAY 0.872340 (-1702 1525);
PAINT GREEN (-1702 1525);
DISPLAY INVISIBLE (-1702 1525);
FORCEADD TAP..3
(-300 3900);
FORCEPROP 3 LASTPIN (-300 3850) SIG_NAME P3E_CPU0_PE2_SS_TXN<13>
J 0
(-290 3860);
DISPLAY 0.659574 (-290 3860);
PAINT MONO (-290 3860);
DISPLAY INVISIBLE (-290 3860);
FORCEPROP 1 LASTPIN (-300 3850) BN 13
R 1
J 0
(-307 3838);
DISPLAY 0.617021 (-307 3838);
PAINT GREEN (-307 3838);
FORCEPROP 2 LAST CDS_LIB mstr_standard
J 0
(-300 3900);
PAINT ORANGE (-300 3900);
DISPLAY INVISIBLE (-300 3900);
FORCEPROP 1 LAST BODY_TYPE PLUMBING
J 0
(-250 3850);
DISPLAY 2.276596 (-250 3850);
PAINT GREEN (-250 3850);
DISPLAY INVISIBLE (-250 3850);
FORCEPROP 1 LAST HDL_TAP TRUE
J 0
(20 3770);
DISPLAY 2.276596 (20 3770);
PAINT GREEN (20 3770);
DISPLAY INVISIBLE (20 3770);
FORCEPROP 1 LAST PATH I18
J 0
(-302 3900);
DISPLAY 0.872340 (-302 3900);
PAINT GREEN (-302 3900);
DISPLAY INVISIBLE (-302 3900);
FORCEADD CAP..1
R 2
(-1700 1275);
FORCEPROP 1 LAST LOCATION C6B16
J 2
(-1750 1375);
DISPLAY 0.617021 (-1750 1375);
PAINT AQUA (-1750 1375);
FORCEPROP 1 LAST PART_NUMBER A36096-155
J 2
(-1750 1125);
DISPLAY 0.617021 (-1750 1125);
PAINT BLUE (-1750 1125);
FORCEPROP 1 LAST VALUE 0.22UF
J 2
(-1750 1325);
DISPLAY 0.617021 (-1750 1325);
PAINT SKYBLUE (-1750 1325);
FORCEPROP 1 LAST TOLERANCE 10%
J 2
(-1750 1225);
DISPLAY 0.617021 (-1750 1225);
PAINT SKYBLUE (-1750 1225);
FORCEPROP 1 LAST PACK_TYPE 0402
J 2
(-1750 1075);
DISPLAY 0.617021 (-1750 1075);
PAINT SKYBLUE (-1750 1075);
FORCEPROP 1 LAST VOLTAGE 16V
J 2
(-1750 1275);
DISPLAY 0.617021 (-1750 1275);
PAINT SKYBLUE (-1750 1275);
FORCEPROP 1 LAST MATERIAL X7R
J 2
(-1750 1175);
DISPLAY 0.617021 (-1750 1175);
PAINT SKYBLUE (-1750 1175);
FORCEPROP 1 LASTPIN (-1700 1175) $PN 2
J 2
(-1710 1155);
DISPLAY 0.617021 (-1710 1155);
PAINT ORANGE (-1710 1155);
FORCEPROP 1 LASTPIN (-1700 1375) $PN 1
J 2
(-1710 1355);
DISPLAY 0.617021 (-1710 1355);
PAINT ORANGE (-1710 1355);
FORCEPROP 2 LAST SEC_TYPE 0402
J 0
(-1750 1475);
DISPLAY 1.021277 (-1750 1475);
PAINT ORANGE (-1750 1475);
DISPLAY INVISIBLE (-1750 1475);
FORCEPROP 2 LAST CDS_LIB mstr_discrete
J 0
(-1700 1275);
PAINT ORANGE (-1700 1275);
DISPLAY INVISIBLE (-1700 1275);
FORCEPROP 2 LAST SEC 1
J 0
(-1750 1475);
DISPLAY 0.680851 (-1750 1475);
PAINT MONO (-1750 1475);
DISPLAY INVISIBLE (-1750 1475);
FORCEPROP 2 LAST CDS_LOCATION C6B16
J 2
(-1750 1375);
DISPLAY 0.617021 (-1750 1375);
PAINT AQUA (-1750 1375);
DISPLAY INVISIBLE (-1750 1375);
FORCEPROP 1 LAST PATH I180
J 2
(-1750 1425);
DISPLAY 0.978723 (-1750 1425);
PAINT WHITE (-1750 1425);
DISPLAY INVISIBLE (-1750 1425);
FORCEPROP 2 LAST ROOM OCP_STEERING
J 2
(-1700 1275);
PAINT MONO (-1700 1275);
DISPLAY INVISIBLE (-1700 1275);
FORCEADD CAP..1
R 2
(-1950 1975);
FORCEPROP 1 LAST LOCATION C6B14
J 2
(-2000 2075);
DISPLAY 0.617021 (-2000 2075);
PAINT AQUA (-2000 2075);
FORCEPROP 1 LAST PART_NUMBER A36096-155
J 2
(-2000 1825);
DISPLAY 0.617021 (-2000 1825);
PAINT BLUE (-2000 1825);
FORCEPROP 1 LAST VALUE 0.22UF
J 2
(-2000 2025);
DISPLAY 0.617021 (-2000 2025);
PAINT SKYBLUE (-2000 2025);
FORCEPROP 1 LAST TOLERANCE 10%
J 2
(-2000 1925);
DISPLAY 0.617021 (-2000 1925);
PAINT SKYBLUE (-2000 1925);
FORCEPROP 1 LAST PACK_TYPE 0402
J 2
(-2000 1775);
DISPLAY 0.617021 (-2000 1775);
PAINT SKYBLUE (-2000 1775);
FORCEPROP 1 LAST VOLTAGE 16V
J 2
(-2000 1975);
DISPLAY 0.617021 (-2000 1975);
PAINT SKYBLUE (-2000 1975);
FORCEPROP 1 LAST MATERIAL X7R
J 2
(-2000 1875);
DISPLAY 0.617021 (-2000 1875);
PAINT SKYBLUE (-2000 1875);
FORCEPROP 1 LASTPIN (-1950 1875) $PN 2
J 2
(-1960 1855);
DISPLAY 0.617021 (-1960 1855);
PAINT ORANGE (-1960 1855);
FORCEPROP 1 LASTPIN (-1950 2075) $PN 1
J 2
(-1960 2055);
DISPLAY 0.617021 (-1960 2055);
PAINT ORANGE (-1960 2055);
FORCEPROP 2 LAST SEC_TYPE 0402
J 0
(-2000 2175);
DISPLAY 1.021277 (-2000 2175);
PAINT ORANGE (-2000 2175);
DISPLAY INVISIBLE (-2000 2175);
FORCEPROP 2 LAST CDS_LIB mstr_discrete
J 0
(-1950 1975);
PAINT ORANGE (-1950 1975);
DISPLAY INVISIBLE (-1950 1975);
FORCEPROP 2 LAST SEC 1
J 0
(-2000 2175);
DISPLAY 0.680851 (-2000 2175);
PAINT MONO (-2000 2175);
DISPLAY INVISIBLE (-2000 2175);
FORCEPROP 2 LAST CDS_LOCATION C6B14
J 2
(-2000 2075);
DISPLAY 0.617021 (-2000 2075);
PAINT AQUA (-2000 2075);
DISPLAY INVISIBLE (-2000 2075);
FORCEPROP 1 LAST PATH I181
J 2
(-2000 2125);
DISPLAY 0.978723 (-2000 2125);
PAINT WHITE (-2000 2125);
DISPLAY INVISIBLE (-2000 2125);
FORCEPROP 2 LAST ROOM OCP_STEERING
J 2
(-1950 1975);
PAINT MONO (-1950 1975);
DISPLAY INVISIBLE (-1950 1975);
FORCEADD TAP..3
(-1900 1525);
FORCEPROP 3 LASTPIN (-1900 1475) SIG_NAME P3E_CPU0_PE1_PCH_TXP<11>
J 0
(-1890 1485);
DISPLAY 0.659574 (-1890 1485);
PAINT MONO (-1890 1485);
DISPLAY INVISIBLE (-1890 1485);
FORCEPROP 1 LASTPIN (-1900 1475) BN 11
R 1
J 0
(-1907 1463);
DISPLAY 0.617021 (-1907 1463);
PAINT GREEN (-1907 1463);
FORCEPROP 2 LAST CDS_LIB mstr_standard
J 0
(-1900 1525);
PAINT ORANGE (-1900 1525);
DISPLAY INVISIBLE (-1900 1525);
FORCEPROP 1 LAST BODY_TYPE PLUMBING
J 0
(-1850 1475);
DISPLAY 2.276596 (-1850 1475);
PAINT GREEN (-1850 1475);
DISPLAY INVISIBLE (-1850 1475);
FORCEPROP 1 LAST HDL_TAP TRUE
J 0
(-1580 1395);
DISPLAY 2.276596 (-1580 1395);
PAINT GREEN (-1580 1395);
DISPLAY INVISIBLE (-1580 1395);
FORCEPROP 1 LAST PATH I182
J 0
(-1902 1525);
DISPLAY 0.872340 (-1902 1525);
PAINT GREEN (-1902 1525);
DISPLAY INVISIBLE (-1902 1525);
FORCEADD TAP..7
(-1950 1725);
FORCEPROP 3 LASTPIN (-1950 1775) SIG_NAME P3E_CPU0_PE1_PCH_C_TXN<11>
J 0
(-1940 1785);
DISPLAY 0.659574 (-1940 1785);
PAINT MONO (-1940 1785);
DISPLAY INVISIBLE (-1940 1785);
FORCEPROP 1 LASTPIN (-1950 1775) BN 11
R 1
J 0
(-1957 1723);
DISPLAY 0.617021 (-1957 1723);
PAINT GREEN (-1957 1723);
FORCEPROP 2 LAST CDS_LIB mstr_standard
J 0
(-1950 1725);
PAINT ORANGE (-1950 1725);
DISPLAY INVISIBLE (-1950 1725);
FORCEPROP 1 LAST BODY_TYPE PLUMBING
J 0
(-1900 1725);
DISPLAY 2.276596 (-1900 1725);
PAINT GREEN (-1900 1725);
DISPLAY INVISIBLE (-1900 1725);
FORCEPROP 1 LAST HDL_TAP TRUE
J 0
(-1630 1595);
DISPLAY 2.276596 (-1630 1595);
PAINT GREEN (-1630 1595);
DISPLAY INVISIBLE (-1630 1595);
FORCEPROP 1 LAST PATH I183
J 0
(-1952 1725);
DISPLAY 0.872340 (-1952 1725);
PAINT GREEN (-1952 1725);
DISPLAY INVISIBLE (-1952 1725);
FORCEADD TAP..7
(-2150 1725);
FORCEPROP 3 LASTPIN (-2150 1775) SIG_NAME P3E_CPU0_PE1_PCH_C_TXN<12>
J 0
(-2140 1785);
DISPLAY 0.659574 (-2140 1785);
PAINT MONO (-2140 1785);
DISPLAY INVISIBLE (-2140 1785);
FORCEPROP 1 LASTPIN (-2150 1775) BN 12
R 1
J 0
(-2157 1723);
DISPLAY 0.617021 (-2157 1723);
PAINT GREEN (-2157 1723);
FORCEPROP 2 LAST CDS_LIB mstr_standard
J 0
(-2150 1725);
PAINT ORANGE (-2150 1725);
DISPLAY INVISIBLE (-2150 1725);
FORCEPROP 1 LAST BODY_TYPE PLUMBING
J 0
(-2100 1725);
DISPLAY 2.276596 (-2100 1725);
PAINT GREEN (-2100 1725);
DISPLAY INVISIBLE (-2100 1725);
FORCEPROP 1 LAST HDL_TAP TRUE
J 0
(-1830 1595);
DISPLAY 2.276596 (-1830 1595);
PAINT GREEN (-1830 1595);
DISPLAY INVISIBLE (-1830 1595);
FORCEPROP 1 LAST PATH I184
J 0
(-2152 1725);
DISPLAY 0.872340 (-2152 1725);
PAINT GREEN (-2152 1725);
DISPLAY INVISIBLE (-2152 1725);
FORCEADD CAP..1
R 2
(-2350 1975);
FORCEPROP 1 LAST LOCATION C6B9
J 2
(-2400 2075);
DISPLAY 0.617021 (-2400 2075);
PAINT AQUA (-2400 2075);
FORCEPROP 1 LAST PART_NUMBER A36096-155
J 2
(-2400 1825);
DISPLAY 0.617021 (-2400 1825);
PAINT BLUE (-2400 1825);
FORCEPROP 1 LAST VALUE 0.22UF
J 2
(-2400 2025);
DISPLAY 0.617021 (-2400 2025);
PAINT SKYBLUE (-2400 2025);
FORCEPROP 1 LAST TOLERANCE 10%
J 2
(-2400 1925);
DISPLAY 0.617021 (-2400 1925);
PAINT SKYBLUE (-2400 1925);
FORCEPROP 1 LAST PACK_TYPE 0402
J 2
(-2400 1775);
DISPLAY 0.617021 (-2400 1775);
PAINT SKYBLUE (-2400 1775);
FORCEPROP 1 LAST VOLTAGE 16V
J 2
(-2400 1975);
DISPLAY 0.617021 (-2400 1975);
PAINT SKYBLUE (-2400 1975);
FORCEPROP 1 LAST MATERIAL X7R
J 2
(-2400 1875);
DISPLAY 0.617021 (-2400 1875);
PAINT SKYBLUE (-2400 1875);
FORCEPROP 1 LASTPIN (-2350 1875) $PN 2
J 2
(-2360 1855);
DISPLAY 0.617021 (-2360 1855);
PAINT ORANGE (-2360 1855);
FORCEPROP 1 LASTPIN (-2350 2075) $PN 1
J 2
(-2360 2055);
DISPLAY 0.617021 (-2360 2055);
PAINT ORANGE (-2360 2055);
FORCEPROP 2 LAST SEC_TYPE 0402
J 0
(-2400 2175);
DISPLAY 1.021277 (-2400 2175);
PAINT ORANGE (-2400 2175);
DISPLAY INVISIBLE (-2400 2175);
FORCEPROP 2 LAST CDS_LIB mstr_discrete
J 0
(-2350 1975);
PAINT ORANGE (-2350 1975);
DISPLAY INVISIBLE (-2350 1975);
FORCEPROP 2 LAST SEC 1
J 0
(-2400 2175);
DISPLAY 0.680851 (-2400 2175);
PAINT MONO (-2400 2175);
DISPLAY INVISIBLE (-2400 2175);
FORCEPROP 2 LAST CDS_LOCATION C6B9
J 2
(-2400 2075);
DISPLAY 0.617021 (-2400 2075);
PAINT AQUA (-2400 2075);
DISPLAY INVISIBLE (-2400 2075);
FORCEPROP 1 LAST PATH I185
J 2
(-2400 2125);
DISPLAY 0.978723 (-2400 2125);
PAINT WHITE (-2400 2125);
DISPLAY INVISIBLE (-2400 2125);
FORCEPROP 2 LAST ROOM OCP_STEERING
J 2
(-2350 1975);
PAINT MONO (-2350 1975);
DISPLAY INVISIBLE (-2350 1975);
FORCEADD TAP..3
(-2300 1525);
FORCEPROP 3 LASTPIN (-2300 1475) SIG_NAME P3E_CPU0_PE1_PCH_TXP<13>
J 0
(-2290 1485);
DISPLAY 0.659574 (-2290 1485);
PAINT MONO (-2290 1485);
DISPLAY INVISIBLE (-2290 1485);
FORCEPROP 1 LASTPIN (-2300 1475) BN 13
R 1
J 0
(-2307 1463);
DISPLAY 0.617021 (-2307 1463);
PAINT GREEN (-2307 1463);
FORCEPROP 2 LAST CDS_LIB mstr_standard
J 0
(-2300 1525);
PAINT ORANGE (-2300 1525);
DISPLAY INVISIBLE (-2300 1525);
FORCEPROP 1 LAST BODY_TYPE PLUMBING
J 0
(-2250 1475);
DISPLAY 2.276596 (-2250 1475);
PAINT GREEN (-2250 1475);
DISPLAY INVISIBLE (-2250 1475);
FORCEPROP 1 LAST HDL_TAP TRUE
J 0
(-1980 1395);
DISPLAY 2.276596 (-1980 1395);
PAINT GREEN (-1980 1395);
DISPLAY INVISIBLE (-1980 1395);
FORCEPROP 1 LAST PATH I186
J 0
(-2302 1525);
DISPLAY 0.872340 (-2302 1525);
PAINT GREEN (-2302 1525);
DISPLAY INVISIBLE (-2302 1525);
FORCEADD CAP..1
R 2
(-2100 1275);
FORCEPROP 1 LAST LOCATION C6B12
J 2
(-2150 1375);
DISPLAY 0.617021 (-2150 1375);
PAINT AQUA (-2150 1375);
FORCEPROP 1 LAST PART_NUMBER A36096-155
J 2
(-2150 1125);
DISPLAY 0.617021 (-2150 1125);
PAINT BLUE (-2150 1125);
FORCEPROP 1 LAST VALUE 0.22UF
J 2
(-2150 1325);
DISPLAY 0.617021 (-2150 1325);
PAINT SKYBLUE (-2150 1325);
FORCEPROP 1 LAST TOLERANCE 10%
J 2
(-2150 1225);
DISPLAY 0.617021 (-2150 1225);
PAINT SKYBLUE (-2150 1225);
FORCEPROP 1 LAST PACK_TYPE 0402
J 2
(-2150 1075);
DISPLAY 0.617021 (-2150 1075);
PAINT SKYBLUE (-2150 1075);
FORCEPROP 1 LAST VOLTAGE 16V
J 2
(-2150 1275);
DISPLAY 0.617021 (-2150 1275);
PAINT SKYBLUE (-2150 1275);
FORCEPROP 1 LAST MATERIAL X7R
J 2
(-2150 1175);
DISPLAY 0.617021 (-2150 1175);
PAINT SKYBLUE (-2150 1175);
FORCEPROP 1 LASTPIN (-2100 1175) $PN 2
J 2
(-2110 1155);
DISPLAY 0.617021 (-2110 1155);
PAINT ORANGE (-2110 1155);
FORCEPROP 1 LASTPIN (-2100 1375) $PN 1
J 2
(-2110 1355);
DISPLAY 0.617021 (-2110 1355);
PAINT ORANGE (-2110 1355);
FORCEPROP 2 LAST SEC_TYPE 0402
J 0
(-2150 1475);
DISPLAY 1.021277 (-2150 1475);
PAINT ORANGE (-2150 1475);
DISPLAY INVISIBLE (-2150 1475);
FORCEPROP 2 LAST CDS_LIB mstr_discrete
J 0
(-2100 1275);
PAINT ORANGE (-2100 1275);
DISPLAY INVISIBLE (-2100 1275);
FORCEPROP 2 LAST SEC 1
J 0
(-2150 1475);
DISPLAY 0.680851 (-2150 1475);
PAINT MONO (-2150 1475);
DISPLAY INVISIBLE (-2150 1475);
FORCEPROP 2 LAST CDS_LOCATION C6B12
J 2
(-2150 1375);
DISPLAY 0.617021 (-2150 1375);
PAINT AQUA (-2150 1375);
DISPLAY INVISIBLE (-2150 1375);
FORCEPROP 1 LAST PATH I187
J 2
(-2150 1425);
DISPLAY 0.978723 (-2150 1425);
PAINT WHITE (-2150 1425);
DISPLAY INVISIBLE (-2150 1425);
FORCEPROP 2 LAST ROOM OCP_STEERING
J 2
(-2100 1275);
PAINT MONO (-2100 1275);
DISPLAY INVISIBLE (-2100 1275);
FORCEADD TAP..7
(-1500 725);
FORCEPROP 3 LASTPIN (-1500 775) SIG_NAME P3E_CPU0_PE1_PCH_C_TXP<9>
J 0
(-1490 785);
DISPLAY 0.659574 (-1490 785);
PAINT MONO (-1490 785);
DISPLAY INVISIBLE (-1490 785);
FORCEPROP 1 LASTPIN (-1500 775) BN 9
R 1
J 0
(-1507 723);
DISPLAY 0.617021 (-1507 723);
PAINT GREEN (-1507 723);
FORCEPROP 2 LAST CDS_LIB mstr_standard
J 0
(-1500 725);
PAINT ORANGE (-1500 725);
DISPLAY INVISIBLE (-1500 725);
FORCEPROP 1 LAST BODY_TYPE PLUMBING
J 0
(-1450 725);
DISPLAY 2.276596 (-1450 725);
PAINT GREEN (-1450 725);
DISPLAY INVISIBLE (-1450 725);
FORCEPROP 1 LAST HDL_TAP TRUE
J 0
(-1180 595);
DISPLAY 2.276596 (-1180 595);
PAINT GREEN (-1180 595);
DISPLAY INVISIBLE (-1180 595);
FORCEPROP 1 LAST PATH I188
J 0
(-1502 725);
DISPLAY 0.872340 (-1502 725);
PAINT GREEN (-1502 725);
DISPLAY INVISIBLE (-1502 725);
FORCEADD CAP..1
R 2
(-1900 975);
FORCEPROP 1 LAST LOCATION C6B13
J 2
(-1950 1075);
DISPLAY 0.617021 (-1950 1075);
PAINT AQUA (-1950 1075);
FORCEPROP 1 LAST PART_NUMBER A36096-155
J 2
(-1950 825);
DISPLAY 0.617021 (-1950 825);
PAINT BLUE (-1950 825);
FORCEPROP 1 LAST VALUE 0.22UF
J 2
(-1950 1025);
DISPLAY 0.617021 (-1950 1025);
PAINT SKYBLUE (-1950 1025);
FORCEPROP 1 LAST TOLERANCE 10%
J 2
(-1950 925);
DISPLAY 0.617021 (-1950 925);
PAINT SKYBLUE (-1950 925);
FORCEPROP 1 LAST PACK_TYPE 0402
J 2
(-1950 775);
DISPLAY 0.617021 (-1950 775);
PAINT SKYBLUE (-1950 775);
FORCEPROP 1 LAST VOLTAGE 16V
J 2
(-1950 975);
DISPLAY 0.617021 (-1950 975);
PAINT SKYBLUE (-1950 975);
FORCEPROP 1 LAST MATERIAL X7R
J 2
(-1950 875);
DISPLAY 0.617021 (-1950 875);
PAINT SKYBLUE (-1950 875);
FORCEPROP 1 LASTPIN (-1900 875) $PN 2
J 2
(-1910 855);
DISPLAY 0.617021 (-1910 855);
PAINT ORANGE (-1910 855);
FORCEPROP 1 LASTPIN (-1900 1075) $PN 1
J 2
(-1910 1055);
DISPLAY 0.617021 (-1910 1055);
PAINT ORANGE (-1910 1055);
FORCEPROP 2 LAST SEC_TYPE 0402
J 0
(-1950 1175);
DISPLAY 1.021277 (-1950 1175);
PAINT ORANGE (-1950 1175);
DISPLAY INVISIBLE (-1950 1175);
FORCEPROP 2 LAST CDS_LIB mstr_discrete
J 0
(-1900 975);
PAINT ORANGE (-1900 975);
DISPLAY INVISIBLE (-1900 975);
FORCEPROP 2 LAST SEC 1
J 0
(-1950 1175);
DISPLAY 0.680851 (-1950 1175);
PAINT MONO (-1950 1175);
DISPLAY INVISIBLE (-1950 1175);
FORCEPROP 2 LAST CDS_LOCATION C6B13
J 2
(-1950 1075);
DISPLAY 0.617021 (-1950 1075);
PAINT AQUA (-1950 1075);
DISPLAY INVISIBLE (-1950 1075);
FORCEPROP 1 LAST PATH I189
J 2
(-1950 1125);
DISPLAY 0.978723 (-1950 1125);
PAINT WHITE (-1950 1125);
DISPLAY INVISIBLE (-1950 1125);
FORCEPROP 2 LAST ROOM OCP_STEERING
J 2
(-1900 975);
PAINT MONO (-1900 975);
DISPLAY INVISIBLE (-1900 975);
FORCEADD TAP..7
(-350 4100);
FORCEPROP 3 LASTPIN (-350 4150) SIG_NAME P3E_CPU0_PE2_SS_C_TXP<13>
J 0
(-340 4160);
DISPLAY 0.659574 (-340 4160);
PAINT MONO (-340 4160);
DISPLAY INVISIBLE (-340 4160);
FORCEPROP 1 LASTPIN (-350 4150) BN 13
R 1
J 0
(-357 4098);
DISPLAY 0.617021 (-357 4098);
PAINT GREEN (-357 4098);
FORCEPROP 2 LAST CDS_LIB mstr_standard
J 0
(-350 4100);
PAINT ORANGE (-350 4100);
DISPLAY INVISIBLE (-350 4100);
FORCEPROP 1 LAST BODY_TYPE PLUMBING
J 0
(-300 4100);
DISPLAY 2.276596 (-300 4100);
PAINT GREEN (-300 4100);
DISPLAY INVISIBLE (-300 4100);
FORCEPROP 1 LAST HDL_TAP TRUE
J 0
(-30 3970);
DISPLAY 2.276596 (-30 3970);
PAINT GREEN (-30 3970);
DISPLAY INVISIBLE (-30 3970);
FORCEPROP 1 LAST PATH I19
J 0
(-352 4100);
DISPLAY 0.872340 (-352 4100);
PAINT GREEN (-352 4100);
DISPLAY INVISIBLE (-352 4100);
FORCEADD TAP..7
(-1700 725);
FORCEPROP 3 LASTPIN (-1700 775) SIG_NAME P3E_CPU0_PE1_PCH_C_TXP<10>
J 0
(-1690 785);
DISPLAY 0.659574 (-1690 785);
PAINT MONO (-1690 785);
DISPLAY INVISIBLE (-1690 785);
FORCEPROP 1 LASTPIN (-1700 775) BN 10
R 1
J 0
(-1707 723);
DISPLAY 0.617021 (-1707 723);
PAINT GREEN (-1707 723);
FORCEPROP 2 LAST CDS_LIB mstr_standard
J 0
(-1700 725);
PAINT ORANGE (-1700 725);
DISPLAY INVISIBLE (-1700 725);
FORCEPROP 1 LAST BODY_TYPE PLUMBING
J 0
(-1650 725);
DISPLAY 2.276596 (-1650 725);
PAINT GREEN (-1650 725);
DISPLAY INVISIBLE (-1650 725);
FORCEPROP 1 LAST HDL_TAP TRUE
J 0
(-1380 595);
DISPLAY 2.276596 (-1380 595);
PAINT GREEN (-1380 595);
DISPLAY INVISIBLE (-1380 595);
FORCEPROP 1 LAST PATH I190
J 0
(-1702 725);
DISPLAY 0.872340 (-1702 725);
PAINT GREEN (-1702 725);
DISPLAY INVISIBLE (-1702 725);
FORCEADD TAP..7
(-1900 725);
FORCEPROP 3 LASTPIN (-1900 775) SIG_NAME P3E_CPU0_PE1_PCH_C_TXP<11>
J 0
(-1890 785);
DISPLAY 0.659574 (-1890 785);
PAINT MONO (-1890 785);
DISPLAY INVISIBLE (-1890 785);
FORCEPROP 1 LASTPIN (-1900 775) BN 11
R 1
J 0
(-1907 723);
DISPLAY 0.617021 (-1907 723);
PAINT GREEN (-1907 723);
FORCEPROP 2 LAST CDS_LIB mstr_standard
J 0
(-1900 725);
PAINT ORANGE (-1900 725);
DISPLAY INVISIBLE (-1900 725);
FORCEPROP 1 LAST BODY_TYPE PLUMBING
J 0
(-1850 725);
DISPLAY 2.276596 (-1850 725);
PAINT GREEN (-1850 725);
DISPLAY INVISIBLE (-1850 725);
FORCEPROP 1 LAST HDL_TAP TRUE
J 0
(-1580 595);
DISPLAY 2.276596 (-1580 595);
PAINT GREEN (-1580 595);
DISPLAY INVISIBLE (-1580 595);
FORCEPROP 1 LAST PATH I191
J 0
(-1902 725);
DISPLAY 0.872340 (-1902 725);
PAINT GREEN (-1902 725);
DISPLAY INVISIBLE (-1902 725);
FORCEADD TAP..7
(-2100 725);
FORCEPROP 3 LASTPIN (-2100 775) SIG_NAME P3E_CPU0_PE1_PCH_C_TXP<12>
J 0
(-2090 785);
DISPLAY 0.659574 (-2090 785);
PAINT MONO (-2090 785);
DISPLAY INVISIBLE (-2090 785);
FORCEPROP 1 LASTPIN (-2100 775) BN 12
R 1
J 0
(-2107 723);
DISPLAY 0.617021 (-2107 723);
PAINT GREEN (-2107 723);
FORCEPROP 2 LAST CDS_LIB mstr_standard
J 0
(-2100 725);
PAINT ORANGE (-2100 725);
DISPLAY INVISIBLE (-2100 725);
FORCEPROP 1 LAST BODY_TYPE PLUMBING
J 0
(-2050 725);
DISPLAY 2.276596 (-2050 725);
PAINT GREEN (-2050 725);
DISPLAY INVISIBLE (-2050 725);
FORCEPROP 1 LAST HDL_TAP TRUE
J 0
(-1780 595);
DISPLAY 2.276596 (-1780 595);
PAINT GREEN (-1780 595);
DISPLAY INVISIBLE (-1780 595);
FORCEPROP 1 LAST PATH I192
J 0
(-2102 725);
DISPLAY 0.872340 (-2102 725);
PAINT GREEN (-2102 725);
DISPLAY INVISIBLE (-2102 725);
FORCEADD CAP..1
R 2
(-2300 975);
FORCEPROP 1 LAST LOCATION C6B10
J 2
(-2350 1075);
DISPLAY 0.617021 (-2350 1075);
PAINT AQUA (-2350 1075);
FORCEPROP 1 LAST PART_NUMBER A36096-155
J 2
(-2350 825);
DISPLAY 0.617021 (-2350 825);
PAINT BLUE (-2350 825);
FORCEPROP 1 LAST VALUE 0.22UF
J 2
(-2350 1025);
DISPLAY 0.617021 (-2350 1025);
PAINT SKYBLUE (-2350 1025);
FORCEPROP 1 LAST TOLERANCE 10%
J 2
(-2350 925);
DISPLAY 0.617021 (-2350 925);
PAINT SKYBLUE (-2350 925);
FORCEPROP 1 LAST PACK_TYPE 0402
J 2
(-2350 775);
DISPLAY 0.617021 (-2350 775);
PAINT SKYBLUE (-2350 775);
FORCEPROP 1 LAST VOLTAGE 16V
J 2
(-2350 975);
DISPLAY 0.617021 (-2350 975);
PAINT SKYBLUE (-2350 975);
FORCEPROP 1 LAST MATERIAL X7R
J 2
(-2350 875);
DISPLAY 0.617021 (-2350 875);
PAINT SKYBLUE (-2350 875);
FORCEPROP 1 LASTPIN (-2300 875) $PN 2
J 2
(-2310 855);
DISPLAY 0.617021 (-2310 855);
PAINT ORANGE (-2310 855);
FORCEPROP 1 LASTPIN (-2300 1075) $PN 1
J 2
(-2310 1055);
DISPLAY 0.617021 (-2310 1055);
PAINT ORANGE (-2310 1055);
FORCEPROP 2 LAST SEC_TYPE 0402
J 0
(-2350 1175);
DISPLAY 1.021277 (-2350 1175);
PAINT ORANGE (-2350 1175);
DISPLAY INVISIBLE (-2350 1175);
FORCEPROP 2 LAST CDS_LIB mstr_discrete
J 0
(-2300 975);
PAINT ORANGE (-2300 975);
DISPLAY INVISIBLE (-2300 975);
FORCEPROP 2 LAST SEC 1
J 0
(-2350 1175);
DISPLAY 0.680851 (-2350 1175);
PAINT MONO (-2350 1175);
DISPLAY INVISIBLE (-2350 1175);
FORCEPROP 2 LAST CDS_LOCATION C6B10
J 2
(-2350 1075);
DISPLAY 0.617021 (-2350 1075);
PAINT AQUA (-2350 1075);
DISPLAY INVISIBLE (-2350 1075);
FORCEPROP 1 LAST PATH I193
J 2
(-2350 1125);
DISPLAY 0.978723 (-2350 1125);
PAINT WHITE (-2350 1125);
DISPLAY INVISIBLE (-2350 1125);
FORCEPROP 2 LAST ROOM OCP_STEERING
J 2
(-2300 975);
PAINT MONO (-2300 975);
DISPLAY INVISIBLE (-2300 975);
FORCEADD TAP..7
(-2300 725);
FORCEPROP 3 LASTPIN (-2300 775) SIG_NAME P3E_CPU0_PE1_PCH_C_TXP<13>
J 0
(-2290 785);
DISPLAY 0.659574 (-2290 785);
PAINT MONO (-2290 785);
DISPLAY INVISIBLE (-2290 785);
FORCEPROP 1 LASTPIN (-2300 775) BN 13
R 1
J 0
(-2307 723);
DISPLAY 0.617021 (-2307 723);
PAINT GREEN (-2307 723);
FORCEPROP 2 LAST CDS_LIB mstr_standard
J 0
(-2300 725);
PAINT ORANGE (-2300 725);
DISPLAY INVISIBLE (-2300 725);
FORCEPROP 1 LAST BODY_TYPE PLUMBING
J 0
(-2250 725);
DISPLAY 2.276596 (-2250 725);
PAINT GREEN (-2250 725);
DISPLAY INVISIBLE (-2250 725);
FORCEPROP 1 LAST HDL_TAP TRUE
J 0
(-1980 595);
DISPLAY 2.276596 (-1980 595);
PAINT GREEN (-1980 595);
DISPLAY INVISIBLE (-1980 595);
FORCEPROP 1 LAST PATH I194
J 0
(-2302 725);
DISPLAY 0.872340 (-2302 725);
PAINT GREEN (-2302 725);
DISPLAY INVISIBLE (-2302 725);
FORCEADD TAP..3
(-2500 1525);
FORCEPROP 3 LASTPIN (-2500 1475) SIG_NAME P3E_CPU0_PE1_PCH_TXP<14>
J 0
(-2490 1485);
DISPLAY 0.659574 (-2490 1485);
PAINT MONO (-2490 1485);
DISPLAY INVISIBLE (-2490 1485);
FORCEPROP 1 LASTPIN (-2500 1475) BN 14
R 1
J 0
(-2507 1463);
DISPLAY 0.617021 (-2507 1463);
PAINT GREEN (-2507 1463);
FORCEPROP 2 LAST CDS_LIB mstr_standard
J 0
(-2500 1525);
PAINT ORANGE (-2500 1525);
DISPLAY INVISIBLE (-2500 1525);
FORCEPROP 1 LAST BODY_TYPE PLUMBING
J 0
(-2450 1475);
DISPLAY 2.276596 (-2450 1475);
PAINT GREEN (-2450 1475);
DISPLAY INVISIBLE (-2450 1475);
FORCEPROP 1 LAST HDL_TAP TRUE
J 0
(-2180 1395);
DISPLAY 2.276596 (-2180 1395);
PAINT GREEN (-2180 1395);
DISPLAY INVISIBLE (-2180 1395);
FORCEPROP 1 LAST PATH I195
J 0
(-2502 1525);
DISPLAY 0.872340 (-2502 1525);
PAINT GREEN (-2502 1525);
DISPLAY INVISIBLE (-2502 1525);
FORCEADD CAP..1
R 2
(-2750 1975);
FORCEPROP 1 LAST LOCATION C6B4
J 2
(-2800 2075);
DISPLAY 0.617021 (-2800 2075);
PAINT AQUA (-2800 2075);
FORCEPROP 1 LAST PART_NUMBER A36096-155
J 2
(-2800 1825);
DISPLAY 0.617021 (-2800 1825);
PAINT BLUE (-2800 1825);
FORCEPROP 1 LAST VALUE 0.22UF
J 2
(-2800 2025);
DISPLAY 0.617021 (-2800 2025);
PAINT SKYBLUE (-2800 2025);
FORCEPROP 1 LAST TOLERANCE 10%
J 2
(-2800 1925);
DISPLAY 0.617021 (-2800 1925);
PAINT SKYBLUE (-2800 1925);
FORCEPROP 1 LAST PACK_TYPE 0402
J 2
(-2800 1775);
DISPLAY 0.617021 (-2800 1775);
PAINT SKYBLUE (-2800 1775);
FORCEPROP 1 LAST VOLTAGE 16V
J 2
(-2800 1975);
DISPLAY 0.617021 (-2800 1975);
PAINT SKYBLUE (-2800 1975);
FORCEPROP 1 LAST MATERIAL X7R
J 2
(-2800 1875);
DISPLAY 0.617021 (-2800 1875);
PAINT SKYBLUE (-2800 1875);
FORCEPROP 1 LASTPIN (-2750 1875) $PN 2
J 2
(-2760 1855);
DISPLAY 0.617021 (-2760 1855);
PAINT ORANGE (-2760 1855);
FORCEPROP 1 LASTPIN (-2750 2075) $PN 1
J 2
(-2760 2055);
DISPLAY 0.617021 (-2760 2055);
PAINT ORANGE (-2760 2055);
FORCEPROP 2 LAST SEC_TYPE 0402
J 0
(-2800 2175);
DISPLAY 1.021277 (-2800 2175);
PAINT ORANGE (-2800 2175);
DISPLAY INVISIBLE (-2800 2175);
FORCEPROP 2 LAST CDS_LIB mstr_discrete
J 0
(-2750 1975);
PAINT ORANGE (-2750 1975);
DISPLAY INVISIBLE (-2750 1975);
FORCEPROP 2 LAST SEC 1
J 0
(-2800 2175);
DISPLAY 0.680851 (-2800 2175);
PAINT MONO (-2800 2175);
DISPLAY INVISIBLE (-2800 2175);
FORCEPROP 2 LAST CDS_LOCATION C6B4
J 2
(-2800 2075);
DISPLAY 0.617021 (-2800 2075);
PAINT AQUA (-2800 2075);
DISPLAY INVISIBLE (-2800 2075);
FORCEPROP 1 LAST PATH I196
J 2
(-2800 2125);
DISPLAY 0.978723 (-2800 2125);
PAINT WHITE (-2800 2125);
DISPLAY INVISIBLE (-2800 2125);
FORCEPROP 2 LAST ROOM OCP_STEERING
J 2
(-2750 1975);
PAINT MONO (-2750 1975);
DISPLAY INVISIBLE (-2750 1975);
FORCEADD TAP..3
(-2700 1525);
FORCEPROP 3 LASTPIN (-2700 1475) SIG_NAME P3E_CPU0_PE1_PCH_TXP<15>
J 0
(-2690 1485);
DISPLAY 0.659574 (-2690 1485);
PAINT MONO (-2690 1485);
DISPLAY INVISIBLE (-2690 1485);
FORCEPROP 1 LASTPIN (-2700 1475) BN 15
R 1
J 0
(-2707 1463);
DISPLAY 0.617021 (-2707 1463);
PAINT GREEN (-2707 1463);
FORCEPROP 2 LAST CDS_LIB mstr_standard
J 0
(-2700 1525);
PAINT ORANGE (-2700 1525);
DISPLAY INVISIBLE (-2700 1525);
FORCEPROP 1 LAST BODY_TYPE PLUMBING
J 0
(-2650 1475);
DISPLAY 2.276596 (-2650 1475);
PAINT GREEN (-2650 1475);
DISPLAY INVISIBLE (-2650 1475);
FORCEPROP 1 LAST HDL_TAP TRUE
J 0
(-2380 1395);
DISPLAY 2.276596 (-2380 1395);
PAINT GREEN (-2380 1395);
DISPLAY INVISIBLE (-2380 1395);
FORCEPROP 1 LAST PATH I197
J 0
(-2702 1525);
DISPLAY 0.872340 (-2702 1525);
PAINT GREEN (-2702 1525);
DISPLAY INVISIBLE (-2702 1525);
FORCEADD CAP..1
R 2
(-2500 1275);
FORCEPROP 1 LAST LOCATION C6B8
J 2
(-2550 1375);
DISPLAY 0.617021 (-2550 1375);
PAINT AQUA (-2550 1375);
FORCEPROP 1 LAST PART_NUMBER A36096-155
J 2
(-2550 1125);
DISPLAY 0.617021 (-2550 1125);
PAINT BLUE (-2550 1125);
FORCEPROP 1 LAST VALUE 0.22UF
J 2
(-2550 1325);
DISPLAY 0.617021 (-2550 1325);
PAINT SKYBLUE (-2550 1325);
FORCEPROP 1 LAST TOLERANCE 10%
J 2
(-2550 1225);
DISPLAY 0.617021 (-2550 1225);
PAINT SKYBLUE (-2550 1225);
FORCEPROP 1 LAST PACK_TYPE 0402
J 2
(-2550 1075);
DISPLAY 0.617021 (-2550 1075);
PAINT SKYBLUE (-2550 1075);
FORCEPROP 1 LAST VOLTAGE 16V
J 2
(-2550 1275);
DISPLAY 0.617021 (-2550 1275);
PAINT SKYBLUE (-2550 1275);
FORCEPROP 1 LAST MATERIAL X7R
J 2
(-2550 1175);
DISPLAY 0.617021 (-2550 1175);
PAINT SKYBLUE (-2550 1175);
FORCEPROP 1 LASTPIN (-2500 1175) $PN 2
J 2
(-2510 1155);
DISPLAY 0.617021 (-2510 1155);
PAINT ORANGE (-2510 1155);
FORCEPROP 1 LASTPIN (-2500 1375) $PN 1
J 2
(-2510 1355);
DISPLAY 0.617021 (-2510 1355);
PAINT ORANGE (-2510 1355);
FORCEPROP 2 LAST SEC_TYPE 0402
J 0
(-2550 1475);
DISPLAY 1.021277 (-2550 1475);
PAINT ORANGE (-2550 1475);
DISPLAY INVISIBLE (-2550 1475);
FORCEPROP 2 LAST CDS_LIB mstr_discrete
J 0
(-2500 1275);
PAINT ORANGE (-2500 1275);
DISPLAY INVISIBLE (-2500 1275);
FORCEPROP 2 LAST SEC 1
J 0
(-2550 1475);
DISPLAY 0.680851 (-2550 1475);
PAINT MONO (-2550 1475);
DISPLAY INVISIBLE (-2550 1475);
FORCEPROP 2 LAST CDS_LOCATION C6B8
J 2
(-2550 1375);
DISPLAY 0.617021 (-2550 1375);
PAINT AQUA (-2550 1375);
DISPLAY INVISIBLE (-2550 1375);
FORCEPROP 1 LAST PATH I198
J 2
(-2550 1425);
DISPLAY 0.978723 (-2550 1425);
PAINT WHITE (-2550 1425);
DISPLAY INVISIBLE (-2550 1425);
FORCEPROP 2 LAST ROOM OCP_STEERING
J 2
(-2500 1275);
PAINT MONO (-2500 1275);
DISPLAY INVISIBLE (-2500 1275);
FORCEADD OFFPAGE..1
(-2875 1575);
FORCEPROP 2 LAST $XR0 30 
J 0
(-3096 1575);
DISPLAY 0.638298 (-3096 1575);
PAINT MONO (-3096 1575);
FORCEPROP 2 LAST $XR1 244 
J 0
(-3096 1575);
DISPLAY 0.638298 (-3096 1575);
PAINT MONO (-3096 1575);
FORCEPROP 2 LAST CDS_LIB mstr_standard
J 0
(-2875 1575);
PAINT ORANGE (-2875 1575);
DISPLAY INVISIBLE (-2875 1575);
FORCEPROP 1 LAST OFFPAGE TRUE
J 0
(-2555 1445);
PAINT GREEN (-2555 1445);
DISPLAY INVISIBLE (-2555 1445);
FORCEPROP 1 LAST COMMENT_BODY TRUE
J 0
(-2755 1475);
DISPLAY 2.276596 (-2755 1475);
PAINT GREEN (-2755 1475);
DISPLAY INVISIBLE (-2755 1475);
FORCEPROP 2 LAST PATH I199
J 0
(-2825 1650);
DISPLAY 1.021277 (-2825 1650);
PAINT ORANGE (-2825 1650);
DISPLAY INVISIBLE (-2825 1650);
FORCEADD CAP..1
R 2
(-750 4350);
FORCEPROP 1 LAST LOCATION C7G5
J 2
(-800 4450);
DISPLAY 0.617021 (-800 4450);
PAINT AQUA (-800 4450);
FORCEPROP 1 LAST PART_NUMBER A36096-155
J 2
(-800 4200);
DISPLAY 0.617021 (-800 4200);
PAINT BLUE (-800 4200);
FORCEPROP 1 LAST VALUE 0.22UF
J 2
(-800 4400);
DISPLAY 0.617021 (-800 4400);
PAINT SKYBLUE (-800 4400);
FORCEPROP 1 LAST TOLERANCE 10%
J 2
(-800 4300);
DISPLAY 0.617021 (-800 4300);
PAINT SKYBLUE (-800 4300);
FORCEPROP 1 LAST PACK_TYPE 0402
J 2
(-800 4150);
DISPLAY 0.617021 (-800 4150);
PAINT SKYBLUE (-800 4150);
FORCEPROP 1 LAST VOLTAGE 16V
J 2
(-800 4350);
DISPLAY 0.617021 (-800 4350);
PAINT SKYBLUE (-800 4350);
FORCEPROP 1 LAST MATERIAL X7R
J 2
(-800 4250);
DISPLAY 0.617021 (-800 4250);
PAINT SKYBLUE (-800 4250);
FORCEPROP 1 LASTPIN (-750 4250) $PN 2
J 2
(-760 4230);
DISPLAY 0.617021 (-760 4230);
PAINT ORANGE (-760 4230);
FORCEPROP 1 LASTPIN (-750 4450) $PN 1
J 2
(-760 4430);
DISPLAY 0.617021 (-760 4430);
PAINT ORANGE (-760 4430);
FORCEPROP 2 LAST SEC_TYPE 0402
J 0
(-800 4550);
DISPLAY 1.021277 (-800 4550);
PAINT ORANGE (-800 4550);
DISPLAY INVISIBLE (-800 4550);
FORCEPROP 2 LAST CDS_LIB mstr_discrete
J 0
(-750 4350);
PAINT ORANGE (-750 4350);
DISPLAY INVISIBLE (-750 4350);
FORCEPROP 2 LAST SEC 1
J 0
(-800 4550);
DISPLAY 0.680851 (-800 4550);
PAINT MONO (-800 4550);
DISPLAY INVISIBLE (-800 4550);
FORCEPROP 2 LAST CDS_LOCATION C7G5
J 2
(-800 4450);
DISPLAY 0.617021 (-800 4450);
PAINT AQUA (-800 4450);
DISPLAY INVISIBLE (-800 4450);
FORCEPROP 1 LAST PATH I20
J 2
(-800 4500);
DISPLAY 0.978723 (-800 4500);
PAINT WHITE (-800 4500);
DISPLAY INVISIBLE (-800 4500);
FORCEPROP 2 LAST ROOM OCP_STEERING
J 2
(-750 4350);
PAINT MONO (-750 4350);
DISPLAY INVISIBLE (-750 4350);
FORCEADD TAP..7
(-2500 725);
FORCEPROP 3 LASTPIN (-2500 775) SIG_NAME P3E_CPU0_PE1_PCH_C_TXP<14>
J 0
(-2490 785);
DISPLAY 0.659574 (-2490 785);
PAINT MONO (-2490 785);
DISPLAY INVISIBLE (-2490 785);
FORCEPROP 1 LASTPIN (-2500 775) BN 14
R 1
J 0
(-2507 723);
DISPLAY 0.617021 (-2507 723);
PAINT GREEN (-2507 723);
FORCEPROP 2 LAST CDS_LIB mstr_standard
J 0
(-2500 725);
PAINT ORANGE (-2500 725);
DISPLAY INVISIBLE (-2500 725);
FORCEPROP 1 LAST BODY_TYPE PLUMBING
J 0
(-2450 725);
DISPLAY 2.276596 (-2450 725);
PAINT GREEN (-2450 725);
DISPLAY INVISIBLE (-2450 725);
FORCEPROP 1 LAST HDL_TAP TRUE
J 0
(-2180 595);
DISPLAY 2.276596 (-2180 595);
PAINT GREEN (-2180 595);
DISPLAY INVISIBLE (-2180 595);
FORCEPROP 1 LAST PATH I200
J 0
(-2502 725);
DISPLAY 0.872340 (-2502 725);
PAINT GREEN (-2502 725);
DISPLAY INVISIBLE (-2502 725);
FORCEADD CAP..1
R 2
(-2700 975);
FORCEPROP 1 LAST LOCATION C6B5
J 2
(-2750 1075);
DISPLAY 0.617021 (-2750 1075);
PAINT AQUA (-2750 1075);
FORCEPROP 1 LAST PART_NUMBER A36096-155
J 2
(-2750 825);
DISPLAY 0.617021 (-2750 825);
PAINT BLUE (-2750 825);
FORCEPROP 1 LAST VALUE 0.22UF
J 2
(-2750 1025);
DISPLAY 0.617021 (-2750 1025);
PAINT SKYBLUE (-2750 1025);
FORCEPROP 1 LAST TOLERANCE 10%
J 2
(-2750 925);
DISPLAY 0.617021 (-2750 925);
PAINT SKYBLUE (-2750 925);
FORCEPROP 1 LAST PACK_TYPE 0402
J 2
(-2750 775);
DISPLAY 0.617021 (-2750 775);
PAINT SKYBLUE (-2750 775);
FORCEPROP 1 LAST VOLTAGE 16V
J 2
(-2750 975);
DISPLAY 0.617021 (-2750 975);
PAINT SKYBLUE (-2750 975);
FORCEPROP 1 LAST MATERIAL X7R
J 2
(-2750 875);
DISPLAY 0.617021 (-2750 875);
PAINT SKYBLUE (-2750 875);
FORCEPROP 1 LASTPIN (-2700 875) $PN 2
J 2
(-2710 855);
DISPLAY 0.617021 (-2710 855);
PAINT ORANGE (-2710 855);
FORCEPROP 1 LASTPIN (-2700 1075) $PN 1
J 2
(-2710 1055);
DISPLAY 0.617021 (-2710 1055);
PAINT ORANGE (-2710 1055);
FORCEPROP 2 LAST SEC_TYPE 0402
J 0
(-2750 1175);
DISPLAY 1.021277 (-2750 1175);
PAINT ORANGE (-2750 1175);
DISPLAY INVISIBLE (-2750 1175);
FORCEPROP 2 LAST CDS_LIB mstr_discrete
J 0
(-2700 975);
PAINT ORANGE (-2700 975);
DISPLAY INVISIBLE (-2700 975);
FORCEPROP 2 LAST SEC 1
J 0
(-2750 1175);
DISPLAY 0.680851 (-2750 1175);
PAINT MONO (-2750 1175);
DISPLAY INVISIBLE (-2750 1175);
FORCEPROP 2 LAST CDS_LOCATION C6B5
J 2
(-2750 1075);
DISPLAY 0.617021 (-2750 1075);
PAINT AQUA (-2750 1075);
DISPLAY INVISIBLE (-2750 1075);
FORCEPROP 1 LAST PATH I201
J 2
(-2750 1125);
DISPLAY 0.978723 (-2750 1125);
PAINT WHITE (-2750 1125);
DISPLAY INVISIBLE (-2750 1125);
FORCEPROP 2 LAST ROOM OCP_STEERING
J 2
(-2700 975);
PAINT MONO (-2700 975);
DISPLAY INVISIBLE (-2700 975);
FORCEADD TAP..7
(-2700 725);
FORCEPROP 3 LASTPIN (-2700 775) SIG_NAME P3E_CPU0_PE1_PCH_C_TXP<15>
J 0
(-2690 785);
DISPLAY 0.659574 (-2690 785);
PAINT MONO (-2690 785);
DISPLAY INVISIBLE (-2690 785);
FORCEPROP 1 LASTPIN (-2700 775) BN 15
R 1
J 0
(-2707 723);
DISPLAY 0.617021 (-2707 723);
PAINT GREEN (-2707 723);
FORCEPROP 2 LAST CDS_LIB mstr_standard
J 0
(-2700 725);
PAINT ORANGE (-2700 725);
DISPLAY INVISIBLE (-2700 725);
FORCEPROP 1 LAST BODY_TYPE PLUMBING
J 0
(-2650 725);
DISPLAY 2.276596 (-2650 725);
PAINT GREEN (-2650 725);
DISPLAY INVISIBLE (-2650 725);
FORCEPROP 1 LAST HDL_TAP TRUE
J 0
(-2380 595);
DISPLAY 2.276596 (-2380 595);
PAINT GREEN (-2380 595);
DISPLAY INVISIBLE (-2380 595);
FORCEPROP 1 LAST PATH I202
J 0
(-2702 725);
DISPLAY 0.872340 (-2702 725);
PAINT GREEN (-2702 725);
DISPLAY INVISIBLE (-2702 725);
FORCEADD OFFPAGE..2
(-1050 1675);
FORCEPROP 2 LAST $XR0 117 
J 0
(-861 1675);
DISPLAY 0.638298 (-861 1675);
PAINT MONO (-861 1675);
FORCEPROP 2 LAST CDS_LIB mstr_standard
J 0
(-1050 1675);
PAINT ORANGE (-1050 1675);
DISPLAY INVISIBLE (-1050 1675);
FORCEPROP 1 LAST OFFPAGE TRUE
J 0
(-725 1550);
DISPLAY 0.872340 (-725 1550);
PAINT GREEN (-725 1550);
DISPLAY INVISIBLE (-725 1550);
FORCEPROP 1 LAST COMMENT_BODY TRUE
J 0
(-1095 1580);
DISPLAY 0.872340 (-1095 1580);
PAINT GREEN (-1095 1580);
DISPLAY INVISIBLE (-1095 1580);
FORCEPROP 2 LAST PATH I203
J 0
(-875 1750);
DISPLAY 1.021277 (-875 1750);
PAINT ORANGE (-875 1750);
DISPLAY INVISIBLE (-875 1750);
FORCEADD OFFPAGE..2
(-1000 675);
FORCEPROP 2 LAST $XR0 117 
J 0
(-811 675);
DISPLAY 0.638298 (-811 675);
PAINT MONO (-811 675);
FORCEPROP 2 LAST CDS_LIB mstr_standard
J 0
(-1000 675);
PAINT ORANGE (-1000 675);
DISPLAY INVISIBLE (-1000 675);
FORCEPROP 1 LAST OFFPAGE TRUE
J 0
(-675 550);
DISPLAY 0.872340 (-675 550);
PAINT GREEN (-675 550);
DISPLAY INVISIBLE (-675 550);
FORCEPROP 1 LAST COMMENT_BODY TRUE
J 0
(-1045 580);
DISPLAY 0.872340 (-1045 580);
PAINT GREEN (-1045 580);
DISPLAY INVISIBLE (-1045 580);
FORCEPROP 2 LAST PATH I204
J 0
(-825 750);
DISPLAY 1.021277 (-825 750);
PAINT ORANGE (-825 750);
DISPLAY INVISIBLE (-825 750);
FORCEADD CAP..1
R 2
(1800 2025);
FORCEPROP 1 LAST LOCATION C3M25
J 2
(1750 2125);
DISPLAY 0.617021 (1750 2125);
PAINT AQUA (1750 2125);
FORCEPROP 1 LAST PART_NUMBER A36096-155
J 2
(1750 1875);
DISPLAY 0.617021 (1750 1875);
PAINT BLUE (1750 1875);
FORCEPROP 1 LAST VALUE 0.22UF
J 2
(1750 2075);
DISPLAY 0.617021 (1750 2075);
PAINT SKYBLUE (1750 2075);
FORCEPROP 1 LAST TOLERANCE 10%
J 2
(1750 1975);
DISPLAY 0.617021 (1750 1975);
PAINT SKYBLUE (1750 1975);
FORCEPROP 1 LAST PACK_TYPE 0402
J 2
(1750 1825);
DISPLAY 0.617021 (1750 1825);
PAINT SKYBLUE (1750 1825);
FORCEPROP 1 LAST VOLTAGE 16V
J 2
(1750 2025);
DISPLAY 0.617021 (1750 2025);
PAINT SKYBLUE (1750 2025);
FORCEPROP 1 LAST MATERIAL X7R
J 2
(1750 1925);
DISPLAY 0.617021 (1750 1925);
PAINT SKYBLUE (1750 1925);
FORCEPROP 1 LASTPIN (1800 1925) $PN 2
J 2
(1790 1905);
DISPLAY 0.617021 (1790 1905);
PAINT ORANGE (1790 1905);
FORCEPROP 1 LASTPIN (1800 2125) $PN 1
J 2
(1790 2105);
DISPLAY 0.617021 (1790 2105);
PAINT ORANGE (1790 2105);
FORCEPROP 2 LAST CDS_LIB mstr_discrete
J 0
(1800 2025);
PAINT ORANGE (1800 2025);
DISPLAY INVISIBLE (1800 2025);
FORCEPROP 2 LAST CDS_SEC 1
J 0
(1750 2225);
DISPLAY 1.021277 (1750 2225);
PAINT ORANGE (1750 2225);
DISPLAY INVISIBLE (1750 2225);
FORCEPROP 2 LAST $SEC 1
J 0
(1750 2225);
DISPLAY 0.680851 (1750 2225);
PAINT MONO (1750 2225);
DISPLAY INVISIBLE (1750 2225);
FORCEPROP 2 LAST CDS_LOCATION C3M25
J 2
(1750 2125);
DISPLAY 0.617021 (1750 2125);
PAINT AQUA (1750 2125);
DISPLAY INVISIBLE (1750 2125);
FORCEPROP 1 LAST PATH I205
J 2
(1750 2175);
DISPLAY 0.978723 (1750 2175);
PAINT WHITE (1750 2175);
DISPLAY INVISIBLE (1750 2175);
FORCEPROP 2 LAST ROOM OCP_STEERING
J 2
(1800 2025);
PAINT MONO (1800 2025);
DISPLAY INVISIBLE (1800 2025);
FORCEADD CAP..1
R 2
(2400 2325);
FORCEPROP 1 LAST LOCATION C3M34
J 2
(2350 2425);
DISPLAY 0.617021 (2350 2425);
PAINT AQUA (2350 2425);
FORCEPROP 1 LAST PART_NUMBER A36096-155
J 2
(2350 2175);
DISPLAY 0.617021 (2350 2175);
PAINT BLUE (2350 2175);
FORCEPROP 1 LAST VALUE 0.22UF
J 2
(2350 2375);
DISPLAY 0.617021 (2350 2375);
PAINT SKYBLUE (2350 2375);
FORCEPROP 1 LAST TOLERANCE 10%
J 2
(2350 2275);
DISPLAY 0.617021 (2350 2275);
PAINT SKYBLUE (2350 2275);
FORCEPROP 1 LAST PACK_TYPE 0402
J 2
(2350 2125);
DISPLAY 0.617021 (2350 2125);
PAINT SKYBLUE (2350 2125);
FORCEPROP 1 LAST VOLTAGE 16V
J 2
(2350 2325);
DISPLAY 0.617021 (2350 2325);
PAINT SKYBLUE (2350 2325);
FORCEPROP 1 LAST MATERIAL X7R
J 2
(2350 2225);
DISPLAY 0.617021 (2350 2225);
PAINT SKYBLUE (2350 2225);
FORCEPROP 1 LASTPIN (2400 2225) $PN 2
J 2
(2390 2205);
DISPLAY 0.617021 (2390 2205);
PAINT ORANGE (2390 2205);
FORCEPROP 1 LASTPIN (2400 2425) $PN 1
J 2
(2390 2405);
DISPLAY 0.617021 (2390 2405);
PAINT ORANGE (2390 2405);
FORCEPROP 2 LAST CDS_LIB mstr_discrete
J 0
(2400 2325);
PAINT ORANGE (2400 2325);
DISPLAY INVISIBLE (2400 2325);
FORCEPROP 2 LAST CDS_SEC 1
J 0
(2350 2525);
DISPLAY 1.021277 (2350 2525);
PAINT ORANGE (2350 2525);
DISPLAY INVISIBLE (2350 2525);
FORCEPROP 2 LAST $SEC 1
J 0
(2350 2525);
DISPLAY 0.680851 (2350 2525);
PAINT MONO (2350 2525);
DISPLAY INVISIBLE (2350 2525);
FORCEPROP 2 LAST CDS_LOCATION C3M34
J 2
(2350 2425);
DISPLAY 0.617021 (2350 2425);
PAINT AQUA (2350 2425);
DISPLAY INVISIBLE (2350 2425);
FORCEPROP 1 LAST PATH I206
J 2
(2350 2475);
DISPLAY 0.978723 (2350 2475);
PAINT WHITE (2350 2475);
DISPLAY INVISIBLE (2350 2475);
FORCEPROP 2 LAST ROOM OCP_STEERING
J 2
(2400 2325);
PAINT MONO (2400 2325);
DISPLAY INVISIBLE (2400 2325);
FORCEADD OFFPAGE..2
(2700 1725);
FORCEPROP 2 LAST $XR0 30 
J 0
(2889 1725);
DISPLAY 0.638298 (2889 1725);
PAINT MONO (2889 1725);
FORCEPROP 2 LAST $XR1 244 
J 0
(2889 1725);
DISPLAY 0.638298 (2889 1725);
PAINT MONO (2889 1725);
FORCEPROP 2 LAST CDS_LIB mstr_standard
J 0
(2700 1725);
PAINT ORANGE (2700 1725);
DISPLAY INVISIBLE (2700 1725);
FORCEPROP 1 LAST OFFPAGE TRUE
J 0
(3025 1600);
DISPLAY 0.872340 (3025 1600);
PAINT GREEN (3025 1600);
DISPLAY INVISIBLE (3025 1600);
FORCEPROP 1 LAST COMMENT_BODY TRUE
J 0
(2655 1630);
DISPLAY 0.872340 (2655 1630);
PAINT GREEN (2655 1630);
DISPLAY INVISIBLE (2655 1630);
FORCEPROP 2 LAST PATH I207
J 0
(2875 1800);
DISPLAY 1.021277 (2875 1800);
PAINT ORANGE (2875 1800);
DISPLAY INVISIBLE (2875 1800);
FORCEADD OFFPAGE..2
(2750 725);
FORCEPROP 2 LAST $XR0 30 
J 0
(2939 725);
DISPLAY 0.638298 (2939 725);
PAINT MONO (2939 725);
FORCEPROP 2 LAST $XR1 244 
J 0
(2939 725);
DISPLAY 0.638298 (2939 725);
PAINT MONO (2939 725);
FORCEPROP 2 LAST CDS_LIB mstr_standard
J 0
(2750 725);
PAINT ORANGE (2750 725);
DISPLAY INVISIBLE (2750 725);
FORCEPROP 1 LAST OFFPAGE TRUE
J 0
(3075 600);
DISPLAY 0.872340 (3075 600);
PAINT GREEN (3075 600);
DISPLAY INVISIBLE (3075 600);
FORCEPROP 1 LAST COMMENT_BODY TRUE
J 0
(2705 630);
DISPLAY 0.872340 (2705 630);
PAINT GREEN (2705 630);
DISPLAY INVISIBLE (2705 630);
FORCEPROP 2 LAST PATH I208
J 0
(2925 800);
DISPLAY 1.021277 (2925 800);
PAINT ORANGE (2925 800);
DISPLAY INVISIBLE (2925 800);
FORCEADD TAP..3
(2400 2575);
FORCEPROP 3 LASTPIN (2400 2525) SIG_NAME P3E_CPU0_PE1_PCH_R_RXP<8>
J 0
(2410 2535);
DISPLAY 0.659574 (2410 2535);
PAINT MONO (2410 2535);
DISPLAY INVISIBLE (2410 2535);
FORCEPROP 1 LASTPIN (2400 2525) BN 8
R 1
J 0
(2393 2513);
DISPLAY 0.617021 (2393 2513);
PAINT GREEN (2393 2513);
FORCEPROP 2 LAST CDS_LIB mstr_standard
J 0
(2400 2575);
PAINT ORANGE (2400 2575);
DISPLAY INVISIBLE (2400 2575);
FORCEPROP 1 LAST BODY_TYPE PLUMBING
J 0
(2450 2525);
DISPLAY 2.276596 (2450 2525);
PAINT GREEN (2450 2525);
DISPLAY INVISIBLE (2450 2525);
FORCEPROP 1 LAST HDL_TAP TRUE
J 0
(2720 2445);
DISPLAY 2.276596 (2720 2445);
PAINT GREEN (2720 2445);
DISPLAY INVISIBLE (2720 2445);
FORCEPROP 1 LAST PATH I209
J 0
(2398 2575);
DISPLAY 0.872340 (2398 2575);
PAINT GREEN (2398 2575);
DISPLAY INVISIBLE (2398 2575);
FORCEADD CAP..1
R 2
(-350 4350);
FORCEPROP 1 LAST LOCATION C7G9
J 2
(-400 4450);
DISPLAY 0.617021 (-400 4450);
PAINT AQUA (-400 4450);
FORCEPROP 1 LAST PART_NUMBER A36096-155
J 2
(-400 4200);
DISPLAY 0.617021 (-400 4200);
PAINT BLUE (-400 4200);
FORCEPROP 1 LAST VALUE 0.22UF
J 2
(-400 4400);
DISPLAY 0.617021 (-400 4400);
PAINT SKYBLUE (-400 4400);
FORCEPROP 1 LAST TOLERANCE 10%
J 2
(-400 4300);
DISPLAY 0.617021 (-400 4300);
PAINT SKYBLUE (-400 4300);
FORCEPROP 1 LAST PACK_TYPE 0402
J 2
(-400 4150);
DISPLAY 0.617021 (-400 4150);
PAINT SKYBLUE (-400 4150);
FORCEPROP 1 LAST VOLTAGE 16V
J 2
(-400 4350);
DISPLAY 0.617021 (-400 4350);
PAINT SKYBLUE (-400 4350);
FORCEPROP 1 LAST MATERIAL X7R
J 2
(-400 4250);
DISPLAY 0.617021 (-400 4250);
PAINT SKYBLUE (-400 4250);
FORCEPROP 1 LASTPIN (-350 4250) $PN 2
J 2
(-360 4230);
DISPLAY 0.617021 (-360 4230);
PAINT ORANGE (-360 4230);
FORCEPROP 1 LASTPIN (-350 4450) $PN 1
J 2
(-360 4430);
DISPLAY 0.617021 (-360 4430);
PAINT ORANGE (-360 4430);
FORCEPROP 2 LAST SEC_TYPE 0402
J 0
(-400 4550);
DISPLAY 1.021277 (-400 4550);
PAINT ORANGE (-400 4550);
DISPLAY INVISIBLE (-400 4550);
FORCEPROP 2 LAST CDS_LIB mstr_discrete
J 0
(-350 4350);
PAINT ORANGE (-350 4350);
DISPLAY INVISIBLE (-350 4350);
FORCEPROP 2 LAST SEC 1
J 0
(-400 4550);
DISPLAY 0.680851 (-400 4550);
PAINT MONO (-400 4550);
DISPLAY INVISIBLE (-400 4550);
FORCEPROP 2 LAST CDS_LOCATION C7G9
J 2
(-400 4450);
DISPLAY 0.617021 (-400 4450);
PAINT AQUA (-400 4450);
DISPLAY INVISIBLE (-400 4450);
FORCEPROP 1 LAST PATH I21
J 2
(-400 4500);
DISPLAY 0.978723 (-400 4500);
PAINT WHITE (-400 4500);
DISPLAY INVISIBLE (-400 4500);
FORCEPROP 2 LAST ROOM OCP_STEERING
J 2
(-350 4350);
PAINT MONO (-350 4350);
DISPLAY INVISIBLE (-350 4350);
FORCEADD TAP..3
(2200 2575);
FORCEPROP 3 LASTPIN (2200 2525) SIG_NAME P3E_CPU0_PE1_PCH_R_RXP<9>
J 0
(2210 2535);
DISPLAY 0.659574 (2210 2535);
PAINT MONO (2210 2535);
DISPLAY INVISIBLE (2210 2535);
FORCEPROP 1 LASTPIN (2200 2525) BN 9
R 1
J 0
(2193 2513);
DISPLAY 0.617021 (2193 2513);
PAINT GREEN (2193 2513);
FORCEPROP 2 LAST CDS_LIB mstr_standard
J 0
(2200 2575);
PAINT ORANGE (2200 2575);
DISPLAY INVISIBLE (2200 2575);
FORCEPROP 1 LAST BODY_TYPE PLUMBING
J 0
(2250 2525);
DISPLAY 2.276596 (2250 2525);
PAINT GREEN (2250 2525);
DISPLAY INVISIBLE (2250 2525);
FORCEPROP 1 LAST HDL_TAP TRUE
J 0
(2520 2445);
DISPLAY 2.276596 (2520 2445);
PAINT GREEN (2520 2445);
DISPLAY INVISIBLE (2520 2445);
FORCEPROP 1 LAST PATH I210
J 0
(2198 2575);
DISPLAY 0.872340 (2198 2575);
PAINT GREEN (2198 2575);
DISPLAY INVISIBLE (2198 2575);
FORCEADD TAP..3
(2000 2575);
FORCEPROP 3 LASTPIN (2000 2525) SIG_NAME P3E_CPU0_PE1_PCH_R_RXP<10>
J 0
(2010 2535);
DISPLAY 0.659574 (2010 2535);
PAINT MONO (2010 2535);
DISPLAY INVISIBLE (2010 2535);
FORCEPROP 1 LASTPIN (2000 2525) BN 10
R 1
J 0
(1993 2513);
DISPLAY 0.617021 (1993 2513);
PAINT GREEN (1993 2513);
FORCEPROP 2 LAST CDS_LIB mstr_standard
J 0
(2000 2575);
PAINT ORANGE (2000 2575);
DISPLAY INVISIBLE (2000 2575);
FORCEPROP 1 LAST BODY_TYPE PLUMBING
J 0
(2050 2525);
DISPLAY 2.276596 (2050 2525);
PAINT GREEN (2050 2525);
DISPLAY INVISIBLE (2050 2525);
FORCEPROP 1 LAST HDL_TAP TRUE
J 0
(2320 2445);
DISPLAY 2.276596 (2320 2445);
PAINT GREEN (2320 2445);
DISPLAY INVISIBLE (2320 2445);
FORCEPROP 1 LAST PATH I211
J 0
(1998 2575);
DISPLAY 0.872340 (1998 2575);
PAINT GREEN (1998 2575);
DISPLAY INVISIBLE (1998 2575);
FORCEADD CAP..1
R 2
(2000 2325);
FORCEPROP 1 LAST LOCATION C3M28
J 2
(1950 2425);
DISPLAY 0.617021 (1950 2425);
PAINT AQUA (1950 2425);
FORCEPROP 1 LAST PART_NUMBER A36096-155
J 2
(1950 2175);
DISPLAY 0.617021 (1950 2175);
PAINT BLUE (1950 2175);
FORCEPROP 1 LAST VALUE 0.22UF
J 2
(1950 2375);
DISPLAY 0.617021 (1950 2375);
PAINT SKYBLUE (1950 2375);
FORCEPROP 1 LAST TOLERANCE 10%
J 2
(1950 2275);
DISPLAY 0.617021 (1950 2275);
PAINT SKYBLUE (1950 2275);
FORCEPROP 1 LAST PACK_TYPE 0402
J 2
(1950 2125);
DISPLAY 0.617021 (1950 2125);
PAINT SKYBLUE (1950 2125);
FORCEPROP 1 LAST VOLTAGE 16V
J 2
(1950 2325);
DISPLAY 0.617021 (1950 2325);
PAINT SKYBLUE (1950 2325);
FORCEPROP 1 LAST MATERIAL X7R
J 2
(1950 2225);
DISPLAY 0.617021 (1950 2225);
PAINT SKYBLUE (1950 2225);
FORCEPROP 1 LASTPIN (2000 2225) $PN 2
J 2
(1990 2205);
DISPLAY 0.617021 (1990 2205);
PAINT ORANGE (1990 2205);
FORCEPROP 1 LASTPIN (2000 2425) $PN 1
J 2
(1990 2405);
DISPLAY 0.617021 (1990 2405);
PAINT ORANGE (1990 2405);
FORCEPROP 2 LAST CDS_LIB mstr_discrete
J 0
(2000 2325);
PAINT ORANGE (2000 2325);
DISPLAY INVISIBLE (2000 2325);
FORCEPROP 2 LAST CDS_SEC 1
J 0
(1950 2525);
DISPLAY 1.021277 (1950 2525);
PAINT ORANGE (1950 2525);
DISPLAY INVISIBLE (1950 2525);
FORCEPROP 2 LAST $SEC 1
J 0
(1950 2525);
DISPLAY 0.680851 (1950 2525);
PAINT MONO (1950 2525);
DISPLAY INVISIBLE (1950 2525);
FORCEPROP 2 LAST CDS_LOCATION C3M28
J 2
(1950 2425);
DISPLAY 0.617021 (1950 2425);
PAINT AQUA (1950 2425);
DISPLAY INVISIBLE (1950 2425);
FORCEPROP 1 LAST PATH I212
J 2
(1950 2475);
DISPLAY 0.978723 (1950 2475);
PAINT WHITE (1950 2475);
DISPLAY INVISIBLE (1950 2475);
FORCEPROP 2 LAST ROOM OCP_STEERING
J 2
(2000 2325);
PAINT MONO (2000 2325);
DISPLAY INVISIBLE (2000 2325);
FORCEADD TAP..3
(1800 2575);
FORCEPROP 3 LASTPIN (1800 2525) SIG_NAME P3E_CPU0_PE1_PCH_R_RXP<11>
J 0
(1810 2535);
DISPLAY 0.659574 (1810 2535);
PAINT MONO (1810 2535);
DISPLAY INVISIBLE (1810 2535);
FORCEPROP 1 LASTPIN (1800 2525) BN 11
R 1
J 0
(1793 2513);
DISPLAY 0.617021 (1793 2513);
PAINT GREEN (1793 2513);
FORCEPROP 2 LAST CDS_LIB mstr_standard
J 0
(1800 2575);
PAINT ORANGE (1800 2575);
DISPLAY INVISIBLE (1800 2575);
FORCEPROP 1 LAST BODY_TYPE PLUMBING
J 0
(1850 2525);
DISPLAY 2.276596 (1850 2525);
PAINT GREEN (1850 2525);
DISPLAY INVISIBLE (1850 2525);
FORCEPROP 1 LAST HDL_TAP TRUE
J 0
(2120 2445);
DISPLAY 2.276596 (2120 2445);
PAINT GREEN (2120 2445);
DISPLAY INVISIBLE (2120 2445);
FORCEPROP 1 LAST PATH I213
J 0
(1798 2575);
DISPLAY 0.872340 (1798 2575);
PAINT GREEN (1798 2575);
DISPLAY INVISIBLE (1798 2575);
FORCEADD TAP..7
(2400 1775);
FORCEPROP 3 LASTPIN (2400 1825) SIG_NAME P3E_CPU0_PE1_PCH_RXP<8>
J 0
(2410 1835);
DISPLAY 0.659574 (2410 1835);
PAINT MONO (2410 1835);
DISPLAY INVISIBLE (2410 1835);
FORCEPROP 1 LASTPIN (2400 1825) BN 8
R 1
J 0
(2393 1773);
DISPLAY 0.617021 (2393 1773);
PAINT GREEN (2393 1773);
FORCEPROP 2 LAST CDS_LIB mstr_standard
J 0
(2400 1775);
PAINT ORANGE (2400 1775);
DISPLAY INVISIBLE (2400 1775);
FORCEPROP 1 LAST BODY_TYPE PLUMBING
J 0
(2450 1775);
DISPLAY 2.276596 (2450 1775);
PAINT GREEN (2450 1775);
DISPLAY INVISIBLE (2450 1775);
FORCEPROP 1 LAST HDL_TAP TRUE
J 0
(2720 1645);
DISPLAY 2.276596 (2720 1645);
PAINT GREEN (2720 1645);
DISPLAY INVISIBLE (2720 1645);
FORCEPROP 1 LAST PATH I214
J 0
(2398 1775);
DISPLAY 0.872340 (2398 1775);
PAINT GREEN (2398 1775);
DISPLAY INVISIBLE (2398 1775);
FORCEADD TAP..3
(2450 1575);
FORCEPROP 3 LASTPIN (2450 1525) SIG_NAME P3E_CPU0_PE1_PCH_R_RXN<8>
J 0
(2460 1535);
DISPLAY 0.659574 (2460 1535);
PAINT MONO (2460 1535);
DISPLAY INVISIBLE (2460 1535);
FORCEPROP 1 LASTPIN (2450 1525) BN 8
R 1
J 0
(2443 1513);
DISPLAY 0.617021 (2443 1513);
PAINT GREEN (2443 1513);
FORCEPROP 2 LAST CDS_LIB mstr_standard
J 0
(2450 1575);
PAINT ORANGE (2450 1575);
DISPLAY INVISIBLE (2450 1575);
FORCEPROP 1 LAST BODY_TYPE PLUMBING
J 0
(2500 1525);
DISPLAY 2.276596 (2500 1525);
PAINT GREEN (2500 1525);
DISPLAY INVISIBLE (2500 1525);
FORCEPROP 1 LAST HDL_TAP TRUE
J 0
(2770 1445);
DISPLAY 2.276596 (2770 1445);
PAINT GREEN (2770 1445);
DISPLAY INVISIBLE (2770 1445);
FORCEPROP 1 LAST PATH I215
J 0
(2448 1575);
DISPLAY 0.872340 (2448 1575);
PAINT GREEN (2448 1575);
DISPLAY INVISIBLE (2448 1575);
FORCEADD TAP..3
(2250 1575);
FORCEPROP 3 LASTPIN (2250 1525) SIG_NAME P3E_CPU0_PE1_PCH_R_RXN<9>
J 0
(2260 1535);
DISPLAY 0.659574 (2260 1535);
PAINT MONO (2260 1535);
DISPLAY INVISIBLE (2260 1535);
FORCEPROP 1 LASTPIN (2250 1525) BN 9
R 1
J 0
(2243 1513);
DISPLAY 0.617021 (2243 1513);
PAINT GREEN (2243 1513);
FORCEPROP 2 LAST CDS_LIB mstr_standard
J 0
(2250 1575);
PAINT ORANGE (2250 1575);
DISPLAY INVISIBLE (2250 1575);
FORCEPROP 1 LAST BODY_TYPE PLUMBING
J 0
(2300 1525);
DISPLAY 2.276596 (2300 1525);
PAINT GREEN (2300 1525);
DISPLAY INVISIBLE (2300 1525);
FORCEPROP 1 LAST HDL_TAP TRUE
J 0
(2570 1445);
DISPLAY 2.276596 (2570 1445);
PAINT GREEN (2570 1445);
DISPLAY INVISIBLE (2570 1445);
FORCEPROP 1 LAST PATH I216
J 0
(2248 1575);
DISPLAY 0.872340 (2248 1575);
PAINT GREEN (2248 1575);
DISPLAY INVISIBLE (2248 1575);
FORCEADD CAP..1
R 2
(2450 1325);
FORCEPROP 1 LAST LOCATION C3M33
J 2
(2400 1425);
DISPLAY 0.617021 (2400 1425);
PAINT AQUA (2400 1425);
FORCEPROP 1 LAST PART_NUMBER A36096-155
J 2
(2400 1175);
DISPLAY 0.617021 (2400 1175);
PAINT BLUE (2400 1175);
FORCEPROP 1 LAST VALUE 0.22UF
J 2
(2400 1375);
DISPLAY 0.617021 (2400 1375);
PAINT SKYBLUE (2400 1375);
FORCEPROP 1 LAST TOLERANCE 10%
J 2
(2400 1275);
DISPLAY 0.617021 (2400 1275);
PAINT SKYBLUE (2400 1275);
FORCEPROP 1 LAST PACK_TYPE 0402
J 2
(2400 1125);
DISPLAY 0.617021 (2400 1125);
PAINT SKYBLUE (2400 1125);
FORCEPROP 1 LAST VOLTAGE 16V
J 2
(2400 1325);
DISPLAY 0.617021 (2400 1325);
PAINT SKYBLUE (2400 1325);
FORCEPROP 1 LAST MATERIAL X7R
J 2
(2400 1225);
DISPLAY 0.617021 (2400 1225);
PAINT SKYBLUE (2400 1225);
FORCEPROP 1 LASTPIN (2450 1225) $PN 2
J 2
(2440 1205);
DISPLAY 0.617021 (2440 1205);
PAINT ORANGE (2440 1205);
FORCEPROP 1 LASTPIN (2450 1425) $PN 1
J 2
(2440 1405);
DISPLAY 0.617021 (2440 1405);
PAINT ORANGE (2440 1405);
FORCEPROP 2 LAST CDS_LIB mstr_discrete
J 0
(2450 1325);
PAINT ORANGE (2450 1325);
DISPLAY INVISIBLE (2450 1325);
FORCEPROP 2 LAST CDS_SEC 1
J 0
(2400 1525);
DISPLAY 1.021277 (2400 1525);
PAINT ORANGE (2400 1525);
DISPLAY INVISIBLE (2400 1525);
FORCEPROP 2 LAST $SEC 1
J 0
(2400 1525);
DISPLAY 0.680851 (2400 1525);
PAINT MONO (2400 1525);
DISPLAY INVISIBLE (2400 1525);
FORCEPROP 2 LAST CDS_LOCATION C3M33
J 2
(2400 1425);
DISPLAY 0.617021 (2400 1425);
PAINT AQUA (2400 1425);
DISPLAY INVISIBLE (2400 1425);
FORCEPROP 1 LAST PATH I217
J 2
(2400 1475);
DISPLAY 0.978723 (2400 1475);
PAINT WHITE (2400 1475);
DISPLAY INVISIBLE (2400 1475);
FORCEPROP 2 LAST ROOM OCP_STEERING
J 2
(2450 1325);
PAINT MONO (2450 1325);
DISPLAY INVISIBLE (2450 1325);
FORCEADD CAP..1
R 2
(2200 2025);
FORCEPROP 1 LAST LOCATION C3M36
J 2
(2150 2125);
DISPLAY 0.617021 (2150 2125);
PAINT AQUA (2150 2125);
FORCEPROP 1 LAST PART_NUMBER A36096-155
J 2
(2150 1875);
DISPLAY 0.617021 (2150 1875);
PAINT BLUE (2150 1875);
FORCEPROP 1 LAST VALUE 0.22UF
J 2
(2150 2075);
DISPLAY 0.617021 (2150 2075);
PAINT SKYBLUE (2150 2075);
FORCEPROP 1 LAST TOLERANCE 10%
J 2
(2150 1975);
DISPLAY 0.617021 (2150 1975);
PAINT SKYBLUE (2150 1975);
FORCEPROP 1 LAST PACK_TYPE 0402
J 2
(2150 1825);
DISPLAY 0.617021 (2150 1825);
PAINT SKYBLUE (2150 1825);
FORCEPROP 1 LAST VOLTAGE 16V
J 2
(2150 2025);
DISPLAY 0.617021 (2150 2025);
PAINT SKYBLUE (2150 2025);
FORCEPROP 1 LAST MATERIAL X7R
J 2
(2150 1925);
DISPLAY 0.617021 (2150 1925);
PAINT SKYBLUE (2150 1925);
FORCEPROP 1 LASTPIN (2200 1925) $PN 2
J 2
(2190 1905);
DISPLAY 0.617021 (2190 1905);
PAINT ORANGE (2190 1905);
FORCEPROP 1 LASTPIN (2200 2125) $PN 1
J 2
(2190 2105);
DISPLAY 0.617021 (2190 2105);
PAINT ORANGE (2190 2105);
FORCEPROP 2 LAST CDS_LIB mstr_discrete
J 0
(2200 2025);
PAINT ORANGE (2200 2025);
DISPLAY INVISIBLE (2200 2025);
FORCEPROP 2 LAST CDS_SEC 1
J 0
(2150 2225);
DISPLAY 1.021277 (2150 2225);
PAINT ORANGE (2150 2225);
DISPLAY INVISIBLE (2150 2225);
FORCEPROP 2 LAST $SEC 1
J 0
(2150 2225);
DISPLAY 0.680851 (2150 2225);
PAINT MONO (2150 2225);
DISPLAY INVISIBLE (2150 2225);
FORCEPROP 2 LAST CDS_LOCATION C3M36
J 2
(2150 2125);
DISPLAY 0.617021 (2150 2125);
PAINT AQUA (2150 2125);
DISPLAY INVISIBLE (2150 2125);
FORCEPROP 1 LAST PATH I218
J 2
(2150 2175);
DISPLAY 0.978723 (2150 2175);
PAINT WHITE (2150 2175);
DISPLAY INVISIBLE (2150 2175);
FORCEPROP 2 LAST ROOM OCP_STEERING
J 2
(2200 2025);
PAINT MONO (2200 2025);
DISPLAY INVISIBLE (2200 2025);
FORCEADD TAP..7
(2200 1775);
FORCEPROP 3 LASTPIN (2200 1825) SIG_NAME P3E_CPU0_PE1_PCH_RXP<9>
J 0
(2210 1835);
DISPLAY 0.659574 (2210 1835);
PAINT MONO (2210 1835);
DISPLAY INVISIBLE (2210 1835);
FORCEPROP 1 LASTPIN (2200 1825) BN 9
R 1
J 0
(2193 1773);
DISPLAY 0.617021 (2193 1773);
PAINT GREEN (2193 1773);
FORCEPROP 2 LAST CDS_LIB mstr_standard
J 0
(2200 1775);
PAINT ORANGE (2200 1775);
DISPLAY INVISIBLE (2200 1775);
FORCEPROP 1 LAST BODY_TYPE PLUMBING
J 0
(2250 1775);
DISPLAY 2.276596 (2250 1775);
PAINT GREEN (2250 1775);
DISPLAY INVISIBLE (2250 1775);
FORCEPROP 1 LAST HDL_TAP TRUE
J 0
(2520 1645);
DISPLAY 2.276596 (2520 1645);
PAINT GREEN (2520 1645);
DISPLAY INVISIBLE (2520 1645);
FORCEPROP 1 LAST PATH I219
J 0
(2198 1775);
DISPLAY 0.872340 (2198 1775);
PAINT GREEN (2198 1775);
DISPLAY INVISIBLE (2198 1775);
FORCEADD CAP..1
R 2
(-550 4650);
FORCEPROP 1 LAST LOCATION C7G8
J 2
(-600 4750);
DISPLAY 0.617021 (-600 4750);
PAINT AQUA (-600 4750);
FORCEPROP 1 LAST PART_NUMBER A36096-155
J 2
(-600 4500);
DISPLAY 0.617021 (-600 4500);
PAINT BLUE (-600 4500);
FORCEPROP 1 LAST VALUE 0.22UF
J 2
(-600 4700);
DISPLAY 0.617021 (-600 4700);
PAINT SKYBLUE (-600 4700);
FORCEPROP 1 LAST TOLERANCE 10%
J 2
(-600 4600);
DISPLAY 0.617021 (-600 4600);
PAINT SKYBLUE (-600 4600);
FORCEPROP 1 LAST PACK_TYPE 0402
J 2
(-600 4450);
DISPLAY 0.617021 (-600 4450);
PAINT SKYBLUE (-600 4450);
FORCEPROP 1 LAST VOLTAGE 16V
J 2
(-600 4650);
DISPLAY 0.617021 (-600 4650);
PAINT SKYBLUE (-600 4650);
FORCEPROP 1 LAST MATERIAL X7R
J 2
(-600 4550);
DISPLAY 0.617021 (-600 4550);
PAINT SKYBLUE (-600 4550);
FORCEPROP 1 LASTPIN (-550 4550) $PN 2
J 2
(-560 4530);
DISPLAY 0.617021 (-560 4530);
PAINT ORANGE (-560 4530);
FORCEPROP 1 LASTPIN (-550 4750) $PN 1
J 2
(-560 4730);
DISPLAY 0.617021 (-560 4730);
PAINT ORANGE (-560 4730);
FORCEPROP 2 LAST SEC_TYPE 0402
J 0
(-600 4850);
DISPLAY 1.021277 (-600 4850);
PAINT ORANGE (-600 4850);
DISPLAY INVISIBLE (-600 4850);
FORCEPROP 2 LAST CDS_LIB mstr_discrete
J 0
(-550 4650);
PAINT ORANGE (-550 4650);
DISPLAY INVISIBLE (-550 4650);
FORCEPROP 2 LAST SEC 1
J 0
(-600 4850);
DISPLAY 0.680851 (-600 4850);
PAINT MONO (-600 4850);
DISPLAY INVISIBLE (-600 4850);
FORCEPROP 2 LAST CDS_LOCATION C7G8
J 2
(-600 4750);
DISPLAY 0.617021 (-600 4750);
PAINT AQUA (-600 4750);
DISPLAY INVISIBLE (-600 4750);
FORCEPROP 1 LAST PATH I22
J 2
(-600 4800);
DISPLAY 0.978723 (-600 4800);
PAINT WHITE (-600 4800);
DISPLAY INVISIBLE (-600 4800);
FORCEPROP 2 LAST ROOM OCP_STEERING
J 2
(-550 4650);
PAINT MONO (-550 4650);
DISPLAY INVISIBLE (-550 4650);
FORCEADD TAP..7
(2000 1775);
FORCEPROP 3 LASTPIN (2000 1825) SIG_NAME P3E_CPU0_PE1_PCH_RXP<10>
J 0
(2010 1835);
DISPLAY 0.659574 (2010 1835);
PAINT MONO (2010 1835);
DISPLAY INVISIBLE (2010 1835);
FORCEPROP 1 LASTPIN (2000 1825) BN 10
R 1
J 0
(1993 1773);
DISPLAY 0.617021 (1993 1773);
PAINT GREEN (1993 1773);
FORCEPROP 2 LAST CDS_LIB mstr_standard
J 0
(2000 1775);
PAINT ORANGE (2000 1775);
DISPLAY INVISIBLE (2000 1775);
FORCEPROP 1 LAST BODY_TYPE PLUMBING
J 0
(2050 1775);
DISPLAY 2.276596 (2050 1775);
PAINT GREEN (2050 1775);
DISPLAY INVISIBLE (2050 1775);
FORCEPROP 1 LAST HDL_TAP TRUE
J 0
(2320 1645);
DISPLAY 2.276596 (2320 1645);
PAINT GREEN (2320 1645);
DISPLAY INVISIBLE (2320 1645);
FORCEPROP 1 LAST PATH I220
J 0
(1998 1775);
DISPLAY 0.872340 (1998 1775);
PAINT GREEN (1998 1775);
DISPLAY INVISIBLE (1998 1775);
FORCEADD TAP..7
(1800 1775);
FORCEPROP 3 LASTPIN (1800 1825) SIG_NAME P3E_CPU0_PE1_PCH_RXP<11>
J 0
(1810 1835);
DISPLAY 0.659574 (1810 1835);
PAINT MONO (1810 1835);
DISPLAY INVISIBLE (1810 1835);
FORCEPROP 1 LASTPIN (1800 1825) BN 11
R 1
J 0
(1793 1773);
DISPLAY 0.617021 (1793 1773);
PAINT GREEN (1793 1773);
FORCEPROP 2 LAST CDS_LIB mstr_standard
J 0
(1800 1775);
PAINT ORANGE (1800 1775);
DISPLAY INVISIBLE (1800 1775);
FORCEPROP 1 LAST BODY_TYPE PLUMBING
J 0
(1850 1775);
DISPLAY 2.276596 (1850 1775);
PAINT GREEN (1850 1775);
DISPLAY INVISIBLE (1850 1775);
FORCEPROP 1 LAST HDL_TAP TRUE
J 0
(2120 1645);
DISPLAY 2.276596 (2120 1645);
PAINT GREEN (2120 1645);
DISPLAY INVISIBLE (2120 1645);
FORCEPROP 1 LAST PATH I221
J 0
(1798 1775);
DISPLAY 0.872340 (1798 1775);
PAINT GREEN (1798 1775);
DISPLAY INVISIBLE (1798 1775);
FORCEADD TAP..3
(2050 1575);
FORCEPROP 3 LASTPIN (2050 1525) SIG_NAME P3E_CPU0_PE1_PCH_R_RXN<10>
J 0
(2060 1535);
DISPLAY 0.659574 (2060 1535);
PAINT MONO (2060 1535);
DISPLAY INVISIBLE (2060 1535);
FORCEPROP 1 LASTPIN (2050 1525) BN 10
R 1
J 0
(2043 1513);
DISPLAY 0.617021 (2043 1513);
PAINT GREEN (2043 1513);
FORCEPROP 2 LAST CDS_LIB mstr_standard
J 0
(2050 1575);
PAINT ORANGE (2050 1575);
DISPLAY INVISIBLE (2050 1575);
FORCEPROP 1 LAST BODY_TYPE PLUMBING
J 0
(2100 1525);
DISPLAY 2.276596 (2100 1525);
PAINT GREEN (2100 1525);
DISPLAY INVISIBLE (2100 1525);
FORCEPROP 1 LAST HDL_TAP TRUE
J 0
(2370 1445);
DISPLAY 2.276596 (2370 1445);
PAINT GREEN (2370 1445);
DISPLAY INVISIBLE (2370 1445);
FORCEPROP 1 LAST PATH I222
J 0
(2048 1575);
DISPLAY 0.872340 (2048 1575);
PAINT GREEN (2048 1575);
DISPLAY INVISIBLE (2048 1575);
FORCEADD CAP..1
R 2
(2050 1325);
FORCEPROP 1 LAST LOCATION C3M32
J 2
(2000 1425);
DISPLAY 0.617021 (2000 1425);
PAINT AQUA (2000 1425);
FORCEPROP 1 LAST PART_NUMBER A36096-155
J 2
(2000 1175);
DISPLAY 0.617021 (2000 1175);
PAINT BLUE (2000 1175);
FORCEPROP 1 LAST VALUE 0.22UF
J 2
(2000 1375);
DISPLAY 0.617021 (2000 1375);
PAINT SKYBLUE (2000 1375);
FORCEPROP 1 LAST TOLERANCE 10%
J 2
(2000 1275);
DISPLAY 0.617021 (2000 1275);
PAINT SKYBLUE (2000 1275);
FORCEPROP 1 LAST PACK_TYPE 0402
J 2
(2000 1125);
DISPLAY 0.617021 (2000 1125);
PAINT SKYBLUE (2000 1125);
FORCEPROP 1 LAST VOLTAGE 16V
J 2
(2000 1325);
DISPLAY 0.617021 (2000 1325);
PAINT SKYBLUE (2000 1325);
FORCEPROP 1 LAST MATERIAL X7R
J 2
(2000 1225);
DISPLAY 0.617021 (2000 1225);
PAINT SKYBLUE (2000 1225);
FORCEPROP 1 LASTPIN (2050 1225) $PN 2
J 2
(2040 1205);
DISPLAY 0.617021 (2040 1205);
PAINT ORANGE (2040 1205);
FORCEPROP 1 LASTPIN (2050 1425) $PN 1
J 2
(2040 1405);
DISPLAY 0.617021 (2040 1405);
PAINT ORANGE (2040 1405);
FORCEPROP 2 LAST CDS_LIB mstr_discrete
J 0
(2050 1325);
PAINT ORANGE (2050 1325);
DISPLAY INVISIBLE (2050 1325);
FORCEPROP 2 LAST CDS_SEC 1
J 0
(2000 1525);
DISPLAY 1.021277 (2000 1525);
PAINT ORANGE (2000 1525);
DISPLAY INVISIBLE (2000 1525);
FORCEPROP 2 LAST $SEC 1
J 0
(2000 1525);
DISPLAY 0.680851 (2000 1525);
PAINT MONO (2000 1525);
DISPLAY INVISIBLE (2000 1525);
FORCEPROP 2 LAST CDS_LOCATION C3M32
J 2
(2000 1425);
DISPLAY 0.617021 (2000 1425);
PAINT AQUA (2000 1425);
DISPLAY INVISIBLE (2000 1425);
FORCEPROP 1 LAST PATH I223
J 2
(2000 1475);
DISPLAY 0.978723 (2000 1475);
PAINT WHITE (2000 1475);
DISPLAY INVISIBLE (2000 1475);
FORCEPROP 2 LAST ROOM OCP_STEERING
J 2
(2050 1325);
PAINT MONO (2050 1325);
DISPLAY INVISIBLE (2050 1325);
FORCEADD TAP..3
(1850 1575);
FORCEPROP 3 LASTPIN (1850 1525) SIG_NAME P3E_CPU0_PE1_PCH_R_RXN<11>
J 0
(1860 1535);
DISPLAY 0.659574 (1860 1535);
PAINT MONO (1860 1535);
DISPLAY INVISIBLE (1860 1535);
FORCEPROP 1 LASTPIN (1850 1525) BN 11
R 1
J 0
(1843 1513);
DISPLAY 0.617021 (1843 1513);
PAINT GREEN (1843 1513);
FORCEPROP 2 LAST CDS_LIB mstr_standard
J 0
(1850 1575);
PAINT ORANGE (1850 1575);
DISPLAY INVISIBLE (1850 1575);
FORCEPROP 1 LAST BODY_TYPE PLUMBING
J 0
(1900 1525);
DISPLAY 2.276596 (1900 1525);
PAINT GREEN (1900 1525);
DISPLAY INVISIBLE (1900 1525);
FORCEPROP 1 LAST HDL_TAP TRUE
J 0
(2170 1445);
DISPLAY 2.276596 (2170 1445);
PAINT GREEN (2170 1445);
DISPLAY INVISIBLE (2170 1445);
FORCEPROP 1 LAST PATH I224
J 0
(1848 1575);
DISPLAY 0.872340 (1848 1575);
PAINT GREEN (1848 1575);
DISPLAY INVISIBLE (1848 1575);
FORCEADD CAP..1
R 2
(2250 1025);
FORCEPROP 1 LAST LOCATION C3M35
J 2
(2200 1125);
DISPLAY 0.617021 (2200 1125);
PAINT AQUA (2200 1125);
FORCEPROP 1 LAST PART_NUMBER A36096-155
J 2
(2200 875);
DISPLAY 0.617021 (2200 875);
PAINT BLUE (2200 875);
FORCEPROP 1 LAST VALUE 0.22UF
J 2
(2200 1075);
DISPLAY 0.617021 (2200 1075);
PAINT SKYBLUE (2200 1075);
FORCEPROP 1 LAST TOLERANCE 10%
J 2
(2200 975);
DISPLAY 0.617021 (2200 975);
PAINT SKYBLUE (2200 975);
FORCEPROP 1 LAST PACK_TYPE 0402
J 2
(2200 825);
DISPLAY 0.617021 (2200 825);
PAINT SKYBLUE (2200 825);
FORCEPROP 1 LAST VOLTAGE 16V
J 2
(2200 1025);
DISPLAY 0.617021 (2200 1025);
PAINT SKYBLUE (2200 1025);
FORCEPROP 1 LAST MATERIAL X7R
J 2
(2200 925);
DISPLAY 0.617021 (2200 925);
PAINT SKYBLUE (2200 925);
FORCEPROP 1 LASTPIN (2250 925) $PN 2
J 2
(2240 905);
DISPLAY 0.617021 (2240 905);
PAINT ORANGE (2240 905);
FORCEPROP 1 LASTPIN (2250 1125) $PN 1
J 2
(2240 1105);
DISPLAY 0.617021 (2240 1105);
PAINT ORANGE (2240 1105);
FORCEPROP 2 LAST CDS_LIB mstr_discrete
J 0
(2250 1025);
PAINT ORANGE (2250 1025);
DISPLAY INVISIBLE (2250 1025);
FORCEPROP 2 LAST CDS_SEC 1
J 0
(2200 1225);
DISPLAY 1.021277 (2200 1225);
PAINT ORANGE (2200 1225);
DISPLAY INVISIBLE (2200 1225);
FORCEPROP 2 LAST $SEC 1
J 0
(2200 1225);
DISPLAY 0.680851 (2200 1225);
PAINT MONO (2200 1225);
DISPLAY INVISIBLE (2200 1225);
FORCEPROP 2 LAST CDS_LOCATION C3M35
J 2
(2200 1125);
DISPLAY 0.617021 (2200 1125);
PAINT AQUA (2200 1125);
DISPLAY INVISIBLE (2200 1125);
FORCEPROP 1 LAST PATH I225
J 2
(2200 1175);
DISPLAY 0.978723 (2200 1175);
PAINT WHITE (2200 1175);
DISPLAY INVISIBLE (2200 1175);
FORCEPROP 2 LAST ROOM OCP_STEERING
J 2
(2250 1025);
PAINT MONO (2250 1025);
DISPLAY INVISIBLE (2250 1025);
FORCEADD TAP..7
(2250 775);
FORCEPROP 3 LASTPIN (2250 825) SIG_NAME P3E_CPU0_PE1_PCH_RXN<9>
J 0
(2260 835);
DISPLAY 0.659574 (2260 835);
PAINT MONO (2260 835);
DISPLAY INVISIBLE (2260 835);
FORCEPROP 1 LASTPIN (2250 825) BN 9
R 1
J 0
(2243 773);
DISPLAY 0.617021 (2243 773);
PAINT GREEN (2243 773);
FORCEPROP 2 LAST CDS_LIB mstr_standard
J 0
(2250 775);
PAINT ORANGE (2250 775);
DISPLAY INVISIBLE (2250 775);
FORCEPROP 1 LAST BODY_TYPE PLUMBING
J 0
(2300 775);
DISPLAY 2.276596 (2300 775);
PAINT GREEN (2300 775);
DISPLAY INVISIBLE (2300 775);
FORCEPROP 1 LAST HDL_TAP TRUE
J 0
(2570 645);
DISPLAY 2.276596 (2570 645);
PAINT GREEN (2570 645);
DISPLAY INVISIBLE (2570 645);
FORCEPROP 1 LAST PATH I226
J 0
(2248 775);
DISPLAY 0.872340 (2248 775);
PAINT GREEN (2248 775);
DISPLAY INVISIBLE (2248 775);
FORCEADD TAP..7
(2450 775);
FORCEPROP 3 LASTPIN (2450 825) SIG_NAME P3E_CPU0_PE1_PCH_RXN<8>
J 0
(2460 835);
DISPLAY 0.659574 (2460 835);
PAINT MONO (2460 835);
DISPLAY INVISIBLE (2460 835);
FORCEPROP 1 LASTPIN (2450 825) BN 8
R 1
J 0
(2443 773);
DISPLAY 0.617021 (2443 773);
PAINT GREEN (2443 773);
FORCEPROP 2 LAST CDS_LIB mstr_standard
J 0
(2450 775);
PAINT ORANGE (2450 775);
DISPLAY INVISIBLE (2450 775);
FORCEPROP 1 LAST BODY_TYPE PLUMBING
J 0
(2500 775);
DISPLAY 2.276596 (2500 775);
PAINT GREEN (2500 775);
DISPLAY INVISIBLE (2500 775);
FORCEPROP 1 LAST HDL_TAP TRUE
J 0
(2770 645);
DISPLAY 2.276596 (2770 645);
PAINT GREEN (2770 645);
DISPLAY INVISIBLE (2770 645);
FORCEPROP 1 LAST PATH I227
J 0
(2448 775);
DISPLAY 0.872340 (2448 775);
PAINT GREEN (2448 775);
DISPLAY INVISIBLE (2448 775);
FORCEADD TAP..7
(2050 775);
FORCEPROP 3 LASTPIN (2050 825) SIG_NAME P3E_CPU0_PE1_PCH_RXN<10>
J 0
(2060 835);
DISPLAY 0.659574 (2060 835);
PAINT MONO (2060 835);
DISPLAY INVISIBLE (2060 835);
FORCEPROP 1 LASTPIN (2050 825) BN 10
R 1
J 0
(2043 773);
DISPLAY 0.617021 (2043 773);
PAINT GREEN (2043 773);
FORCEPROP 2 LAST CDS_LIB mstr_standard
J 0
(2050 775);
PAINT ORANGE (2050 775);
DISPLAY INVISIBLE (2050 775);
FORCEPROP 1 LAST BODY_TYPE PLUMBING
J 0
(2100 775);
DISPLAY 2.276596 (2100 775);
PAINT GREEN (2100 775);
DISPLAY INVISIBLE (2100 775);
FORCEPROP 1 LAST HDL_TAP TRUE
J 0
(2370 645);
DISPLAY 2.276596 (2370 645);
PAINT GREEN (2370 645);
DISPLAY INVISIBLE (2370 645);
FORCEPROP 1 LAST PATH I228
J 0
(2048 775);
DISPLAY 0.872340 (2048 775);
PAINT GREEN (2048 775);
DISPLAY INVISIBLE (2048 775);
FORCEADD CAP..1
R 2
(1850 1025);
FORCEPROP 1 LAST LOCATION C3M26
J 2
(1800 1125);
DISPLAY 0.617021 (1800 1125);
PAINT AQUA (1800 1125);
FORCEPROP 1 LAST PART_NUMBER A36096-155
J 2
(1800 875);
DISPLAY 0.617021 (1800 875);
PAINT BLUE (1800 875);
FORCEPROP 1 LAST VALUE 0.22UF
J 2
(1800 1075);
DISPLAY 0.617021 (1800 1075);
PAINT SKYBLUE (1800 1075);
FORCEPROP 1 LAST TOLERANCE 10%
J 2
(1800 975);
DISPLAY 0.617021 (1800 975);
PAINT SKYBLUE (1800 975);
FORCEPROP 1 LAST PACK_TYPE 0402
J 2
(1800 825);
DISPLAY 0.617021 (1800 825);
PAINT SKYBLUE (1800 825);
FORCEPROP 1 LAST VOLTAGE 16V
J 2
(1800 1025);
DISPLAY 0.617021 (1800 1025);
PAINT SKYBLUE (1800 1025);
FORCEPROP 1 LAST MATERIAL X7R
J 2
(1800 925);
DISPLAY 0.617021 (1800 925);
PAINT SKYBLUE (1800 925);
FORCEPROP 1 LASTPIN (1850 925) $PN 2
J 2
(1840 905);
DISPLAY 0.617021 (1840 905);
PAINT ORANGE (1840 905);
FORCEPROP 1 LASTPIN (1850 1125) $PN 1
J 2
(1840 1105);
DISPLAY 0.617021 (1840 1105);
PAINT ORANGE (1840 1105);
FORCEPROP 2 LAST CDS_LIB mstr_discrete
J 0
(1850 1025);
PAINT ORANGE (1850 1025);
DISPLAY INVISIBLE (1850 1025);
FORCEPROP 2 LAST CDS_SEC 1
J 0
(1800 1225);
DISPLAY 1.021277 (1800 1225);
PAINT ORANGE (1800 1225);
DISPLAY INVISIBLE (1800 1225);
FORCEPROP 2 LAST $SEC 1
J 0
(1800 1225);
DISPLAY 0.680851 (1800 1225);
PAINT MONO (1800 1225);
DISPLAY INVISIBLE (1800 1225);
FORCEPROP 2 LAST CDS_LOCATION C3M26
J 2
(1800 1125);
DISPLAY 0.617021 (1800 1125);
PAINT AQUA (1800 1125);
DISPLAY INVISIBLE (1800 1125);
FORCEPROP 1 LAST PATH I229
J 2
(1800 1175);
DISPLAY 0.978723 (1800 1175);
PAINT WHITE (1800 1175);
DISPLAY INVISIBLE (1800 1175);
FORCEPROP 2 LAST ROOM OCP_STEERING
J 2
(1850 1025);
PAINT MONO (1850 1025);
DISPLAY INVISIBLE (1850 1025);
FORCEADD TAP..3
(-100 3900);
FORCEPROP 3 LASTPIN (-100 3850) SIG_NAME P3E_CPU0_PE2_SS_TXN<12>
J 0
(-90 3860);
DISPLAY 0.659574 (-90 3860);
PAINT MONO (-90 3860);
DISPLAY INVISIBLE (-90 3860);
FORCEPROP 1 LASTPIN (-100 3850) BN 12
R 1
J 0
(-107 3838);
DISPLAY 0.617021 (-107 3838);
PAINT GREEN (-107 3838);
FORCEPROP 2 LAST CDS_LIB mstr_standard
J 0
(-100 3900);
PAINT ORANGE (-100 3900);
DISPLAY INVISIBLE (-100 3900);
FORCEPROP 1 LAST BODY_TYPE PLUMBING
J 0
(-50 3850);
DISPLAY 2.276596 (-50 3850);
PAINT GREEN (-50 3850);
DISPLAY INVISIBLE (-50 3850);
FORCEPROP 1 LAST HDL_TAP TRUE
J 0
(220 3770);
DISPLAY 2.276596 (220 3770);
PAINT GREEN (220 3770);
DISPLAY INVISIBLE (220 3770);
FORCEPROP 1 LAST PATH I23
J 0
(-102 3900);
DISPLAY 0.872340 (-102 3900);
PAINT GREEN (-102 3900);
DISPLAY INVISIBLE (-102 3900);
FORCEADD TAP..7
(1850 775);
FORCEPROP 3 LASTPIN (1850 825) SIG_NAME P3E_CPU0_PE1_PCH_RXN<11>
J 0
(1860 835);
DISPLAY 0.659574 (1860 835);
PAINT MONO (1860 835);
DISPLAY INVISIBLE (1860 835);
FORCEPROP 1 LASTPIN (1850 825) BN 11
R 1
J 0
(1843 773);
DISPLAY 0.617021 (1843 773);
PAINT GREEN (1843 773);
FORCEPROP 2 LAST CDS_LIB mstr_standard
J 0
(1850 775);
PAINT ORANGE (1850 775);
DISPLAY INVISIBLE (1850 775);
FORCEPROP 1 LAST BODY_TYPE PLUMBING
J 0
(1900 775);
DISPLAY 2.276596 (1900 775);
PAINT GREEN (1900 775);
DISPLAY INVISIBLE (1900 775);
FORCEPROP 1 LAST HDL_TAP TRUE
J 0
(2170 645);
DISPLAY 2.276596 (2170 645);
PAINT GREEN (2170 645);
DISPLAY INVISIBLE (2170 645);
FORCEPROP 1 LAST PATH I230
J 0
(1848 775);
DISPLAY 0.872340 (1848 775);
PAINT GREEN (1848 775);
DISPLAY INVISIBLE (1848 775);
FORCEADD TAP..3
(1600 2575);
FORCEPROP 3 LASTPIN (1600 2525) SIG_NAME P3E_CPU0_PE1_PCH_R_RXP<12>
J 0
(1610 2535);
DISPLAY 0.659574 (1610 2535);
PAINT MONO (1610 2535);
DISPLAY INVISIBLE (1610 2535);
FORCEPROP 1 LASTPIN (1600 2525) BN 12
R 1
J 0
(1593 2513);
DISPLAY 0.617021 (1593 2513);
PAINT GREEN (1593 2513);
FORCEPROP 2 LAST CDS_LIB mstr_standard
J 0
(1600 2575);
PAINT ORANGE (1600 2575);
DISPLAY INVISIBLE (1600 2575);
FORCEPROP 1 LAST BODY_TYPE PLUMBING
J 0
(1650 2525);
DISPLAY 2.276596 (1650 2525);
PAINT GREEN (1650 2525);
DISPLAY INVISIBLE (1650 2525);
FORCEPROP 1 LAST HDL_TAP TRUE
J 0
(1920 2445);
DISPLAY 2.276596 (1920 2445);
PAINT GREEN (1920 2445);
DISPLAY INVISIBLE (1920 2445);
FORCEPROP 1 LAST PATH I231
J 0
(1598 2575);
DISPLAY 0.872340 (1598 2575);
PAINT GREEN (1598 2575);
DISPLAY INVISIBLE (1598 2575);
FORCEADD CAP..1
R 2
(1600 2325);
FORCEPROP 1 LAST LOCATION C3M3
J 2
(1550 2425);
DISPLAY 0.617021 (1550 2425);
PAINT AQUA (1550 2425);
FORCEPROP 1 LAST PART_NUMBER A36096-155
J 2
(1550 2175);
DISPLAY 0.617021 (1550 2175);
PAINT BLUE (1550 2175);
FORCEPROP 1 LAST VALUE 0.22UF
J 2
(1550 2375);
DISPLAY 0.617021 (1550 2375);
PAINT SKYBLUE (1550 2375);
FORCEPROP 1 LAST TOLERANCE 10%
J 2
(1550 2275);
DISPLAY 0.617021 (1550 2275);
PAINT SKYBLUE (1550 2275);
FORCEPROP 1 LAST PACK_TYPE 0402
J 2
(1550 2125);
DISPLAY 0.617021 (1550 2125);
PAINT SKYBLUE (1550 2125);
FORCEPROP 1 LAST VOLTAGE 16V
J 2
(1550 2325);
DISPLAY 0.617021 (1550 2325);
PAINT SKYBLUE (1550 2325);
FORCEPROP 1 LAST MATERIAL X7R
J 2
(1550 2225);
DISPLAY 0.617021 (1550 2225);
PAINT SKYBLUE (1550 2225);
FORCEPROP 1 LASTPIN (1600 2225) $PN 2
J 2
(1590 2205);
DISPLAY 0.617021 (1590 2205);
PAINT ORANGE (1590 2205);
FORCEPROP 1 LASTPIN (1600 2425) $PN 1
J 2
(1590 2405);
DISPLAY 0.617021 (1590 2405);
PAINT ORANGE (1590 2405);
FORCEPROP 2 LAST CDS_LIB mstr_discrete
J 0
(1600 2325);
PAINT ORANGE (1600 2325);
DISPLAY INVISIBLE (1600 2325);
FORCEPROP 2 LAST CDS_SEC 1
J 0
(1550 2525);
DISPLAY 1.021277 (1550 2525);
PAINT ORANGE (1550 2525);
DISPLAY INVISIBLE (1550 2525);
FORCEPROP 2 LAST $SEC 1
J 0
(1550 2525);
DISPLAY 0.680851 (1550 2525);
PAINT MONO (1550 2525);
DISPLAY INVISIBLE (1550 2525);
FORCEPROP 2 LAST CDS_LOCATION C3M3
J 2
(1550 2425);
DISPLAY 0.617021 (1550 2425);
PAINT AQUA (1550 2425);
DISPLAY INVISIBLE (1550 2425);
FORCEPROP 1 LAST PATH I232
J 2
(1550 2475);
DISPLAY 0.978723 (1550 2475);
PAINT WHITE (1550 2475);
DISPLAY INVISIBLE (1550 2475);
FORCEPROP 2 LAST ROOM OCP_STEERING
J 2
(1600 2325);
PAINT MONO (1600 2325);
DISPLAY INVISIBLE (1600 2325);
FORCEADD TAP..3
(1400 2575);
FORCEPROP 3 LASTPIN (1400 2525) SIG_NAME P3E_CPU0_PE1_PCH_R_RXP<13>
J 0
(1410 2535);
DISPLAY 0.659574 (1410 2535);
PAINT MONO (1410 2535);
DISPLAY INVISIBLE (1410 2535);
FORCEPROP 1 LASTPIN (1400 2525) BN 13
R 1
J 0
(1393 2513);
DISPLAY 0.617021 (1393 2513);
PAINT GREEN (1393 2513);
FORCEPROP 2 LAST CDS_LIB mstr_standard
J 0
(1400 2575);
PAINT ORANGE (1400 2575);
DISPLAY INVISIBLE (1400 2575);
FORCEPROP 1 LAST BODY_TYPE PLUMBING
J 0
(1450 2525);
DISPLAY 2.276596 (1450 2525);
PAINT GREEN (1450 2525);
DISPLAY INVISIBLE (1450 2525);
FORCEPROP 1 LAST HDL_TAP TRUE
J 0
(1720 2445);
DISPLAY 2.276596 (1720 2445);
PAINT GREEN (1720 2445);
DISPLAY INVISIBLE (1720 2445);
FORCEPROP 1 LAST PATH I233
J 0
(1398 2575);
DISPLAY 0.872340 (1398 2575);
PAINT GREEN (1398 2575);
DISPLAY INVISIBLE (1398 2575);
FORCEADD CAP..1
R 2
(1200 2325);
FORCEPROP 1 LAST LOCATION C3M11
J 2
(1150 2425);
DISPLAY 0.617021 (1150 2425);
PAINT AQUA (1150 2425);
FORCEPROP 1 LAST PART_NUMBER A36096-155
J 2
(1150 2175);
DISPLAY 0.617021 (1150 2175);
PAINT BLUE (1150 2175);
FORCEPROP 1 LAST VALUE 0.22UF
J 2
(1150 2375);
DISPLAY 0.617021 (1150 2375);
PAINT SKYBLUE (1150 2375);
FORCEPROP 1 LAST TOLERANCE 10%
J 2
(1150 2275);
DISPLAY 0.617021 (1150 2275);
PAINT SKYBLUE (1150 2275);
FORCEPROP 1 LAST PACK_TYPE 0402
J 2
(1150 2125);
DISPLAY 0.617021 (1150 2125);
PAINT SKYBLUE (1150 2125);
FORCEPROP 1 LAST VOLTAGE 16V
J 2
(1150 2325);
DISPLAY 0.617021 (1150 2325);
PAINT SKYBLUE (1150 2325);
FORCEPROP 1 LAST MATERIAL X7R
J 2
(1150 2225);
DISPLAY 0.617021 (1150 2225);
PAINT SKYBLUE (1150 2225);
FORCEPROP 1 LASTPIN (1200 2225) $PN 2
J 2
(1190 2205);
DISPLAY 0.617021 (1190 2205);
PAINT ORANGE (1190 2205);
FORCEPROP 1 LASTPIN (1200 2425) $PN 1
J 2
(1190 2405);
DISPLAY 0.617021 (1190 2405);
PAINT ORANGE (1190 2405);
FORCEPROP 2 LAST CDS_LIB mstr_discrete
J 0
(1200 2325);
PAINT ORANGE (1200 2325);
DISPLAY INVISIBLE (1200 2325);
FORCEPROP 2 LAST CDS_SEC 1
J 0
(1150 2525);
DISPLAY 1.021277 (1150 2525);
PAINT ORANGE (1150 2525);
DISPLAY INVISIBLE (1150 2525);
FORCEPROP 2 LAST $SEC 1
J 0
(1150 2525);
DISPLAY 0.680851 (1150 2525);
PAINT MONO (1150 2525);
DISPLAY INVISIBLE (1150 2525);
FORCEPROP 2 LAST CDS_LOCATION C3M11
J 2
(1150 2425);
DISPLAY 0.617021 (1150 2425);
PAINT AQUA (1150 2425);
DISPLAY INVISIBLE (1150 2425);
FORCEPROP 1 LAST PATH I234
J 2
(1150 2475);
DISPLAY 0.978723 (1150 2475);
PAINT WHITE (1150 2475);
DISPLAY INVISIBLE (1150 2475);
FORCEPROP 2 LAST ROOM OCP_STEERING
J 2
(1200 2325);
PAINT MONO (1200 2325);
DISPLAY INVISIBLE (1200 2325);
FORCEADD TAP..3
(1200 2575);
FORCEPROP 3 LASTPIN (1200 2525) SIG_NAME P3E_CPU0_PE1_PCH_R_RXP<14>
J 0
(1210 2535);
DISPLAY 0.659574 (1210 2535);
PAINT MONO (1210 2535);
DISPLAY INVISIBLE (1210 2535);
FORCEPROP 1 LASTPIN (1200 2525) BN 14
R 1
J 0
(1193 2513);
DISPLAY 0.617021 (1193 2513);
PAINT GREEN (1193 2513);
FORCEPROP 2 LAST CDS_LIB mstr_standard
J 0
(1200 2575);
PAINT ORANGE (1200 2575);
DISPLAY INVISIBLE (1200 2575);
FORCEPROP 1 LAST BODY_TYPE PLUMBING
J 0
(1250 2525);
DISPLAY 2.276596 (1250 2525);
PAINT GREEN (1250 2525);
DISPLAY INVISIBLE (1250 2525);
FORCEPROP 1 LAST HDL_TAP TRUE
J 0
(1520 2445);
DISPLAY 2.276596 (1520 2445);
PAINT GREEN (1520 2445);
DISPLAY INVISIBLE (1520 2445);
FORCEPROP 1 LAST PATH I235
J 0
(1198 2575);
DISPLAY 0.872340 (1198 2575);
PAINT GREEN (1198 2575);
DISPLAY INVISIBLE (1198 2575);
FORCEADD TAP..3
(1000 2575);
FORCEPROP 3 LASTPIN (1000 2525) SIG_NAME P3E_CPU0_PE1_PCH_R_RXP<15>
J 0
(1010 2535);
DISPLAY 0.659574 (1010 2535);
PAINT MONO (1010 2535);
DISPLAY INVISIBLE (1010 2535);
FORCEPROP 1 LASTPIN (1000 2525) BN 15
R 1
J 0
(993 2513);
DISPLAY 0.617021 (993 2513);
PAINT GREEN (993 2513);
FORCEPROP 2 LAST CDS_LIB mstr_standard
J 0
(1000 2575);
PAINT ORANGE (1000 2575);
DISPLAY INVISIBLE (1000 2575);
FORCEPROP 1 LAST BODY_TYPE PLUMBING
J 0
(1050 2525);
DISPLAY 2.276596 (1050 2525);
PAINT GREEN (1050 2525);
DISPLAY INVISIBLE (1050 2525);
FORCEPROP 1 LAST HDL_TAP TRUE
J 0
(1320 2445);
DISPLAY 2.276596 (1320 2445);
PAINT GREEN (1320 2445);
DISPLAY INVISIBLE (1320 2445);
FORCEPROP 1 LAST PATH I236
J 0
(998 2575);
DISPLAY 0.872340 (998 2575);
PAINT GREEN (998 2575);
DISPLAY INVISIBLE (998 2575);
FORCEADD OFFPAGE..1
(825 2625);
FORCEPROP 2 LAST $XR0 117 
J 0
(573 2625);
DISPLAY 0.638298 (573 2625);
PAINT MONO (573 2625);
FORCEPROP 2 LAST CDS_LIB mstr_standard
J 0
(825 2625);
PAINT ORANGE (825 2625);
DISPLAY INVISIBLE (825 2625);
FORCEPROP 1 LAST OFFPAGE TRUE
J 0
(1145 2495);
PAINT GREEN (1145 2495);
DISPLAY INVISIBLE (1145 2495);
FORCEPROP 1 LAST COMMENT_BODY TRUE
J 0
(945 2525);
DISPLAY 2.276596 (945 2525);
PAINT GREEN (945 2525);
DISPLAY INVISIBLE (945 2525);
FORCEPROP 2 LAST PATH I237
J 0
(875 2700);
DISPLAY 1.021277 (875 2700);
PAINT ORANGE (875 2700);
DISPLAY INVISIBLE (875 2700);
FORCEADD TAP..7
(1600 1775);
FORCEPROP 3 LASTPIN (1600 1825) SIG_NAME P3E_CPU0_PE1_PCH_RXP<12>
J 0
(1610 1835);
DISPLAY 0.659574 (1610 1835);
PAINT MONO (1610 1835);
DISPLAY INVISIBLE (1610 1835);
FORCEPROP 1 LASTPIN (1600 1825) BN 12
R 1
J 0
(1593 1773);
DISPLAY 0.617021 (1593 1773);
PAINT GREEN (1593 1773);
FORCEPROP 2 LAST CDS_LIB mstr_standard
J 0
(1600 1775);
PAINT ORANGE (1600 1775);
DISPLAY INVISIBLE (1600 1775);
FORCEPROP 1 LAST BODY_TYPE PLUMBING
J 0
(1650 1775);
DISPLAY 2.276596 (1650 1775);
PAINT GREEN (1650 1775);
DISPLAY INVISIBLE (1650 1775);
FORCEPROP 1 LAST HDL_TAP TRUE
J 0
(1920 1645);
DISPLAY 2.276596 (1920 1645);
PAINT GREEN (1920 1645);
DISPLAY INVISIBLE (1920 1645);
FORCEPROP 1 LAST PATH I238
J 0
(1598 1775);
DISPLAY 0.872340 (1598 1775);
PAINT GREEN (1598 1775);
DISPLAY INVISIBLE (1598 1775);
FORCEADD CAP..1
R 2
(1400 2025);
FORCEPROP 1 LAST LOCATION C3M13
J 2
(1350 2125);
DISPLAY 0.617021 (1350 2125);
PAINT AQUA (1350 2125);
FORCEPROP 1 LAST PART_NUMBER A36096-155
J 2
(1350 1875);
DISPLAY 0.617021 (1350 1875);
PAINT BLUE (1350 1875);
FORCEPROP 1 LAST VALUE 0.22UF
J 2
(1350 2075);
DISPLAY 0.617021 (1350 2075);
PAINT SKYBLUE (1350 2075);
FORCEPROP 1 LAST TOLERANCE 10%
J 2
(1350 1975);
DISPLAY 0.617021 (1350 1975);
PAINT SKYBLUE (1350 1975);
FORCEPROP 1 LAST PACK_TYPE 0402
J 2
(1350 1825);
DISPLAY 0.617021 (1350 1825);
PAINT SKYBLUE (1350 1825);
FORCEPROP 1 LAST VOLTAGE 16V
J 2
(1350 2025);
DISPLAY 0.617021 (1350 2025);
PAINT SKYBLUE (1350 2025);
FORCEPROP 1 LAST MATERIAL X7R
J 2
(1350 1925);
DISPLAY 0.617021 (1350 1925);
PAINT SKYBLUE (1350 1925);
FORCEPROP 1 LASTPIN (1400 1925) $PN 2
J 2
(1390 1905);
DISPLAY 0.617021 (1390 1905);
PAINT ORANGE (1390 1905);
FORCEPROP 1 LASTPIN (1400 2125) $PN 1
J 2
(1390 2105);
DISPLAY 0.617021 (1390 2105);
PAINT ORANGE (1390 2105);
FORCEPROP 2 LAST CDS_LIB mstr_discrete
J 0
(1400 2025);
PAINT ORANGE (1400 2025);
DISPLAY INVISIBLE (1400 2025);
FORCEPROP 2 LAST CDS_SEC 1
J 0
(1350 2225);
DISPLAY 1.021277 (1350 2225);
PAINT ORANGE (1350 2225);
DISPLAY INVISIBLE (1350 2225);
FORCEPROP 2 LAST $SEC 1
J 0
(1350 2225);
DISPLAY 0.680851 (1350 2225);
PAINT MONO (1350 2225);
DISPLAY INVISIBLE (1350 2225);
FORCEPROP 2 LAST CDS_LOCATION C3M13
J 2
(1350 2125);
DISPLAY 0.617021 (1350 2125);
PAINT AQUA (1350 2125);
DISPLAY INVISIBLE (1350 2125);
FORCEPROP 1 LAST PATH I239
J 2
(1350 2175);
DISPLAY 0.978723 (1350 2175);
PAINT WHITE (1350 2175);
DISPLAY INVISIBLE (1350 2175);
FORCEPROP 2 LAST ROOM OCP_STEERING
J 2
(1400 2025);
PAINT MONO (1400 2025);
DISPLAY INVISIBLE (1400 2025);
FORCEADD TAP..7
(-150 4100);
FORCEPROP 3 LASTPIN (-150 4150) SIG_NAME P3E_CPU0_PE2_SS_C_TXP<12>
J 0
(-140 4160);
DISPLAY 0.659574 (-140 4160);
PAINT MONO (-140 4160);
DISPLAY INVISIBLE (-140 4160);
FORCEPROP 1 LASTPIN (-150 4150) BN 12
R 1
J 0
(-157 4098);
DISPLAY 0.617021 (-157 4098);
PAINT GREEN (-157 4098);
FORCEPROP 2 LAST CDS_LIB mstr_standard
J 0
(-150 4100);
PAINT ORANGE (-150 4100);
DISPLAY INVISIBLE (-150 4100);
FORCEPROP 1 LAST BODY_TYPE PLUMBING
J 0
(-100 4100);
DISPLAY 2.276596 (-100 4100);
PAINT GREEN (-100 4100);
DISPLAY INVISIBLE (-100 4100);
FORCEPROP 1 LAST HDL_TAP TRUE
J 0
(170 3970);
DISPLAY 2.276596 (170 3970);
PAINT GREEN (170 3970);
DISPLAY INVISIBLE (170 3970);
FORCEPROP 1 LAST PATH I24
J 0
(-152 4100);
DISPLAY 0.872340 (-152 4100);
PAINT GREEN (-152 4100);
DISPLAY INVISIBLE (-152 4100);
FORCEADD TAP..7
(1400 1775);
FORCEPROP 3 LASTPIN (1400 1825) SIG_NAME P3E_CPU0_PE1_PCH_RXP<13>
J 0
(1410 1835);
DISPLAY 0.659574 (1410 1835);
PAINT MONO (1410 1835);
DISPLAY INVISIBLE (1410 1835);
FORCEPROP 1 LASTPIN (1400 1825) BN 13
R 1
J 0
(1393 1773);
DISPLAY 0.617021 (1393 1773);
PAINT GREEN (1393 1773);
FORCEPROP 2 LAST CDS_LIB mstr_standard
J 0
(1400 1775);
PAINT ORANGE (1400 1775);
DISPLAY INVISIBLE (1400 1775);
FORCEPROP 1 LAST BODY_TYPE PLUMBING
J 0
(1450 1775);
DISPLAY 2.276596 (1450 1775);
PAINT GREEN (1450 1775);
DISPLAY INVISIBLE (1450 1775);
FORCEPROP 1 LAST HDL_TAP TRUE
J 0
(1720 1645);
DISPLAY 2.276596 (1720 1645);
PAINT GREEN (1720 1645);
DISPLAY INVISIBLE (1720 1645);
FORCEPROP 1 LAST PATH I240
J 0
(1398 1775);
DISPLAY 0.872340 (1398 1775);
PAINT GREEN (1398 1775);
DISPLAY INVISIBLE (1398 1775);
FORCEADD TAP..7
(1200 1775);
FORCEPROP 3 LASTPIN (1200 1825) SIG_NAME P3E_CPU0_PE1_PCH_RXP<14>
J 0
(1210 1835);
DISPLAY 0.659574 (1210 1835);
PAINT MONO (1210 1835);
DISPLAY INVISIBLE (1210 1835);
FORCEPROP 1 LASTPIN (1200 1825) BN 14
R 1
J 0
(1193 1773);
DISPLAY 0.617021 (1193 1773);
PAINT GREEN (1193 1773);
FORCEPROP 2 LAST CDS_LIB mstr_standard
J 0
(1200 1775);
PAINT ORANGE (1200 1775);
DISPLAY INVISIBLE (1200 1775);
FORCEPROP 1 LAST BODY_TYPE PLUMBING
J 0
(1250 1775);
DISPLAY 2.276596 (1250 1775);
PAINT GREEN (1250 1775);
DISPLAY INVISIBLE (1250 1775);
FORCEPROP 1 LAST HDL_TAP TRUE
J 0
(1520 1645);
DISPLAY 2.276596 (1520 1645);
PAINT GREEN (1520 1645);
DISPLAY INVISIBLE (1520 1645);
FORCEPROP 1 LAST PATH I241
J 0
(1198 1775);
DISPLAY 0.872340 (1198 1775);
PAINT GREEN (1198 1775);
DISPLAY INVISIBLE (1198 1775);
FORCEADD TAP..3
(1650 1575);
FORCEPROP 3 LASTPIN (1650 1525) SIG_NAME P3E_CPU0_PE1_PCH_R_RXN<12>
J 0
(1660 1535);
DISPLAY 0.659574 (1660 1535);
PAINT MONO (1660 1535);
DISPLAY INVISIBLE (1660 1535);
FORCEPROP 1 LASTPIN (1650 1525) BN 12
R 1
J 0
(1643 1513);
DISPLAY 0.617021 (1643 1513);
PAINT GREEN (1643 1513);
FORCEPROP 2 LAST CDS_LIB mstr_standard
J 0
(1650 1575);
PAINT ORANGE (1650 1575);
DISPLAY INVISIBLE (1650 1575);
FORCEPROP 1 LAST BODY_TYPE PLUMBING
J 0
(1700 1525);
DISPLAY 2.276596 (1700 1525);
PAINT GREEN (1700 1525);
DISPLAY INVISIBLE (1700 1525);
FORCEPROP 1 LAST HDL_TAP TRUE
J 0
(1970 1445);
DISPLAY 2.276596 (1970 1445);
PAINT GREEN (1970 1445);
DISPLAY INVISIBLE (1970 1445);
FORCEPROP 1 LAST PATH I242
J 0
(1648 1575);
DISPLAY 0.872340 (1648 1575);
PAINT GREEN (1648 1575);
DISPLAY INVISIBLE (1648 1575);
FORCEADD TAP..3
(1450 1575);
FORCEPROP 3 LASTPIN (1450 1525) SIG_NAME P3E_CPU0_PE1_PCH_R_RXN<13>
J 0
(1460 1535);
DISPLAY 0.659574 (1460 1535);
PAINT MONO (1460 1535);
DISPLAY INVISIBLE (1460 1535);
FORCEPROP 1 LASTPIN (1450 1525) BN 13
R 1
J 0
(1443 1513);
DISPLAY 0.617021 (1443 1513);
PAINT GREEN (1443 1513);
FORCEPROP 2 LAST CDS_LIB mstr_standard
J 0
(1450 1575);
PAINT ORANGE (1450 1575);
DISPLAY INVISIBLE (1450 1575);
FORCEPROP 1 LAST BODY_TYPE PLUMBING
J 0
(1500 1525);
DISPLAY 2.276596 (1500 1525);
PAINT GREEN (1500 1525);
DISPLAY INVISIBLE (1500 1525);
FORCEPROP 1 LAST HDL_TAP TRUE
J 0
(1770 1445);
DISPLAY 2.276596 (1770 1445);
PAINT GREEN (1770 1445);
DISPLAY INVISIBLE (1770 1445);
FORCEPROP 1 LAST PATH I243
J 0
(1448 1575);
DISPLAY 0.872340 (1448 1575);
PAINT GREEN (1448 1575);
DISPLAY INVISIBLE (1448 1575);
FORCEADD CAP..1
R 2
(1650 1325);
FORCEPROP 1 LAST LOCATION C3M4
J 2
(1600 1425);
DISPLAY 0.617021 (1600 1425);
PAINT AQUA (1600 1425);
FORCEPROP 1 LAST PART_NUMBER A36096-155
J 2
(1600 1175);
DISPLAY 0.617021 (1600 1175);
PAINT BLUE (1600 1175);
FORCEPROP 1 LAST VALUE 0.22UF
J 2
(1600 1375);
DISPLAY 0.617021 (1600 1375);
PAINT SKYBLUE (1600 1375);
FORCEPROP 1 LAST TOLERANCE 10%
J 2
(1600 1275);
DISPLAY 0.617021 (1600 1275);
PAINT SKYBLUE (1600 1275);
FORCEPROP 1 LAST PACK_TYPE 0402
J 2
(1600 1125);
DISPLAY 0.617021 (1600 1125);
PAINT SKYBLUE (1600 1125);
FORCEPROP 1 LAST VOLTAGE 16V
J 2
(1600 1325);
DISPLAY 0.617021 (1600 1325);
PAINT SKYBLUE (1600 1325);
FORCEPROP 1 LAST MATERIAL X7R
J 2
(1600 1225);
DISPLAY 0.617021 (1600 1225);
PAINT SKYBLUE (1600 1225);
FORCEPROP 1 LASTPIN (1650 1225) $PN 2
J 2
(1640 1205);
DISPLAY 0.617021 (1640 1205);
PAINT ORANGE (1640 1205);
FORCEPROP 1 LASTPIN (1650 1425) $PN 1
J 2
(1640 1405);
DISPLAY 0.617021 (1640 1405);
PAINT ORANGE (1640 1405);
FORCEPROP 2 LAST CDS_LIB mstr_discrete
J 0
(1650 1325);
PAINT ORANGE (1650 1325);
DISPLAY INVISIBLE (1650 1325);
FORCEPROP 2 LAST CDS_SEC 1
J 0
(1600 1525);
DISPLAY 1.021277 (1600 1525);
PAINT ORANGE (1600 1525);
DISPLAY INVISIBLE (1600 1525);
FORCEPROP 2 LAST $SEC 1
J 0
(1600 1525);
DISPLAY 0.680851 (1600 1525);
PAINT MONO (1600 1525);
DISPLAY INVISIBLE (1600 1525);
FORCEPROP 2 LAST CDS_LOCATION C3M4
J 2
(1600 1425);
DISPLAY 0.617021 (1600 1425);
PAINT AQUA (1600 1425);
DISPLAY INVISIBLE (1600 1425);
FORCEPROP 1 LAST PATH I244
J 2
(1600 1475);
DISPLAY 0.978723 (1600 1475);
PAINT WHITE (1600 1475);
DISPLAY INVISIBLE (1600 1475);
FORCEPROP 2 LAST ROOM OCP_STEERING
J 2
(1650 1325);
PAINT MONO (1650 1325);
DISPLAY INVISIBLE (1650 1325);
FORCEADD TAP..3
(1250 1575);
FORCEPROP 3 LASTPIN (1250 1525) SIG_NAME P3E_CPU0_PE1_PCH_R_RXN<14>
J 0
(1260 1535);
DISPLAY 0.659574 (1260 1535);
PAINT MONO (1260 1535);
DISPLAY INVISIBLE (1260 1535);
FORCEPROP 1 LASTPIN (1250 1525) BN 14
R 1
J 0
(1243 1513);
DISPLAY 0.617021 (1243 1513);
PAINT GREEN (1243 1513);
FORCEPROP 2 LAST CDS_LIB mstr_standard
J 0
(1250 1575);
PAINT ORANGE (1250 1575);
DISPLAY INVISIBLE (1250 1575);
FORCEPROP 1 LAST BODY_TYPE PLUMBING
J 0
(1300 1525);
DISPLAY 2.276596 (1300 1525);
PAINT GREEN (1300 1525);
DISPLAY INVISIBLE (1300 1525);
FORCEPROP 1 LAST HDL_TAP TRUE
J 0
(1570 1445);
DISPLAY 2.276596 (1570 1445);
PAINT GREEN (1570 1445);
DISPLAY INVISIBLE (1570 1445);
FORCEPROP 1 LAST PATH I245
J 0
(1248 1575);
DISPLAY 0.872340 (1248 1575);
PAINT GREEN (1248 1575);
DISPLAY INVISIBLE (1248 1575);
FORCEADD CAP..1
R 2
(1250 1325);
FORCEPROP 1 LAST LOCATION C3M12
J 2
(1200 1425);
DISPLAY 0.617021 (1200 1425);
PAINT AQUA (1200 1425);
FORCEPROP 1 LAST PART_NUMBER A36096-155
J 2
(1200 1175);
DISPLAY 0.617021 (1200 1175);
PAINT BLUE (1200 1175);
FORCEPROP 1 LAST VALUE 0.22UF
J 2
(1200 1375);
DISPLAY 0.617021 (1200 1375);
PAINT SKYBLUE (1200 1375);
FORCEPROP 1 LAST TOLERANCE 10%
J 2
(1200 1275);
DISPLAY 0.617021 (1200 1275);
PAINT SKYBLUE (1200 1275);
FORCEPROP 1 LAST PACK_TYPE 0402
J 2
(1200 1125);
DISPLAY 0.617021 (1200 1125);
PAINT SKYBLUE (1200 1125);
FORCEPROP 1 LAST VOLTAGE 16V
J 2
(1200 1325);
DISPLAY 0.617021 (1200 1325);
PAINT SKYBLUE (1200 1325);
FORCEPROP 1 LAST MATERIAL X7R
J 2
(1200 1225);
DISPLAY 0.617021 (1200 1225);
PAINT SKYBLUE (1200 1225);
FORCEPROP 1 LASTPIN (1250 1225) $PN 2
J 2
(1240 1205);
DISPLAY 0.617021 (1240 1205);
PAINT ORANGE (1240 1205);
FORCEPROP 1 LASTPIN (1250 1425) $PN 1
J 2
(1240 1405);
DISPLAY 0.617021 (1240 1405);
PAINT ORANGE (1240 1405);
FORCEPROP 2 LAST CDS_LIB mstr_discrete
J 0
(1250 1325);
PAINT ORANGE (1250 1325);
DISPLAY INVISIBLE (1250 1325);
FORCEPROP 2 LAST CDS_SEC 1
J 0
(1200 1525);
DISPLAY 1.021277 (1200 1525);
PAINT ORANGE (1200 1525);
DISPLAY INVISIBLE (1200 1525);
FORCEPROP 2 LAST $SEC 1
J 0
(1200 1525);
DISPLAY 0.680851 (1200 1525);
PAINT MONO (1200 1525);
DISPLAY INVISIBLE (1200 1525);
FORCEPROP 2 LAST CDS_LOCATION C3M12
J 2
(1200 1425);
DISPLAY 0.617021 (1200 1425);
PAINT AQUA (1200 1425);
DISPLAY INVISIBLE (1200 1425);
FORCEPROP 1 LAST PATH I246
J 2
(1200 1475);
DISPLAY 0.978723 (1200 1475);
PAINT WHITE (1200 1475);
DISPLAY INVISIBLE (1200 1475);
FORCEPROP 2 LAST ROOM OCP_STEERING
J 2
(1250 1325);
PAINT MONO (1250 1325);
DISPLAY INVISIBLE (1250 1325);
FORCEADD CAP..1
R 2
(1000 2025);
FORCEPROP 1 LAST LOCATION C3M2
J 2
(950 2125);
DISPLAY 0.617021 (950 2125);
PAINT AQUA (950 2125);
FORCEPROP 1 LAST PART_NUMBER A36096-155
J 2
(950 1875);
DISPLAY 0.617021 (950 1875);
PAINT BLUE (950 1875);
FORCEPROP 1 LAST VALUE 0.22UF
J 2
(950 2075);
DISPLAY 0.617021 (950 2075);
PAINT SKYBLUE (950 2075);
FORCEPROP 1 LAST TOLERANCE 10%
J 2
(950 1975);
DISPLAY 0.617021 (950 1975);
PAINT SKYBLUE (950 1975);
FORCEPROP 1 LAST PACK_TYPE 0402
J 2
(950 1825);
DISPLAY 0.617021 (950 1825);
PAINT SKYBLUE (950 1825);
FORCEPROP 1 LAST VOLTAGE 16V
J 2
(950 2025);
DISPLAY 0.617021 (950 2025);
PAINT SKYBLUE (950 2025);
FORCEPROP 1 LAST MATERIAL X7R
J 2
(950 1925);
DISPLAY 0.617021 (950 1925);
PAINT SKYBLUE (950 1925);
FORCEPROP 1 LASTPIN (1000 1925) $PN 2
J 2
(990 1905);
DISPLAY 0.617021 (990 1905);
PAINT ORANGE (990 1905);
FORCEPROP 1 LASTPIN (1000 2125) $PN 1
J 2
(990 2105);
DISPLAY 0.617021 (990 2105);
PAINT ORANGE (990 2105);
FORCEPROP 2 LAST CDS_LIB mstr_discrete
J 0
(1000 2025);
PAINT ORANGE (1000 2025);
DISPLAY INVISIBLE (1000 2025);
FORCEPROP 2 LAST CDS_SEC 1
J 0
(950 2225);
DISPLAY 1.021277 (950 2225);
PAINT ORANGE (950 2225);
DISPLAY INVISIBLE (950 2225);
FORCEPROP 2 LAST $SEC 1
J 0
(950 2225);
DISPLAY 0.680851 (950 2225);
PAINT MONO (950 2225);
DISPLAY INVISIBLE (950 2225);
FORCEPROP 2 LAST CDS_LOCATION C3M2
J 2
(950 2125);
DISPLAY 0.617021 (950 2125);
PAINT AQUA (950 2125);
DISPLAY INVISIBLE (950 2125);
FORCEPROP 1 LAST PATH I247
J 2
(950 2175);
DISPLAY 0.978723 (950 2175);
PAINT WHITE (950 2175);
DISPLAY INVISIBLE (950 2175);
FORCEPROP 2 LAST ROOM OCP_STEERING
J 2
(1000 2025);
PAINT MONO (1000 2025);
DISPLAY INVISIBLE (1000 2025);
FORCEADD TAP..7
(1000 1775);
FORCEPROP 3 LASTPIN (1000 1825) SIG_NAME P3E_CPU0_PE1_PCH_RXP<15>
J 0
(1010 1835);
DISPLAY 0.659574 (1010 1835);
PAINT MONO (1010 1835);
DISPLAY INVISIBLE (1010 1835);
FORCEPROP 1 LASTPIN (1000 1825) BN 15
R 1
J 0
(993 1773);
DISPLAY 0.617021 (993 1773);
PAINT GREEN (993 1773);
FORCEPROP 2 LAST CDS_LIB mstr_standard
J 0
(1000 1775);
PAINT ORANGE (1000 1775);
DISPLAY INVISIBLE (1000 1775);
FORCEPROP 1 LAST BODY_TYPE PLUMBING
J 0
(1050 1775);
DISPLAY 2.276596 (1050 1775);
PAINT GREEN (1050 1775);
DISPLAY INVISIBLE (1050 1775);
FORCEPROP 1 LAST HDL_TAP TRUE
J 0
(1320 1645);
DISPLAY 2.276596 (1320 1645);
PAINT GREEN (1320 1645);
DISPLAY INVISIBLE (1320 1645);
FORCEPROP 1 LAST PATH I248
J 0
(998 1775);
DISPLAY 0.872340 (998 1775);
PAINT GREEN (998 1775);
DISPLAY INVISIBLE (998 1775);
FORCEADD OFFPAGE..1
(875 1625);
FORCEPROP 2 LAST $XR0 117 
J 0
(593 1625);
DISPLAY 0.638298 (593 1625);
PAINT MONO (593 1625);
FORCEPROP 2 LAST CDS_LIB mstr_standard
J 0
(875 1625);
PAINT ORANGE (875 1625);
DISPLAY INVISIBLE (875 1625);
FORCEPROP 1 LAST OFFPAGE TRUE
J 0
(1195 1495);
PAINT GREEN (1195 1495);
DISPLAY INVISIBLE (1195 1495);
FORCEPROP 1 LAST COMMENT_BODY TRUE
J 0
(995 1525);
DISPLAY 2.276596 (995 1525);
PAINT GREEN (995 1525);
DISPLAY INVISIBLE (995 1525);
FORCEPROP 2 LAST PATH I249
J 0
(925 1700);
DISPLAY 1.021277 (925 1700);
PAINT ORANGE (925 1700);
DISPLAY INVISIBLE (925 1700);
FORCEADD TAP..3
(100 3900);
FORCEPROP 3 LASTPIN (100 3850) SIG_NAME P3E_CPU0_PE2_SS_TXN<11>
J 0
(110 3860);
DISPLAY 0.659574 (110 3860);
PAINT MONO (110 3860);
DISPLAY INVISIBLE (110 3860);
FORCEPROP 1 LASTPIN (100 3850) BN 11
R 1
J 0
(93 3838);
DISPLAY 0.617021 (93 3838);
PAINT GREEN (93 3838);
FORCEPROP 2 LAST CDS_LIB mstr_standard
J 0
(100 3900);
PAINT ORANGE (100 3900);
DISPLAY INVISIBLE (100 3900);
FORCEPROP 1 LAST BODY_TYPE PLUMBING
J 0
(150 3850);
DISPLAY 2.276596 (150 3850);
PAINT GREEN (150 3850);
DISPLAY INVISIBLE (150 3850);
FORCEPROP 1 LAST HDL_TAP TRUE
J 0
(420 3770);
DISPLAY 2.276596 (420 3770);
PAINT GREEN (420 3770);
DISPLAY INVISIBLE (420 3770);
FORCEPROP 1 LAST PATH I25
J 0
(98 3900);
DISPLAY 0.872340 (98 3900);
PAINT GREEN (98 3900);
DISPLAY INVISIBLE (98 3900);
FORCEADD TAP..3
(1050 1575);
FORCEPROP 3 LASTPIN (1050 1525) SIG_NAME P3E_CPU0_PE1_PCH_R_RXN<15>
J 0
(1060 1535);
DISPLAY 0.659574 (1060 1535);
PAINT MONO (1060 1535);
DISPLAY INVISIBLE (1060 1535);
FORCEPROP 1 LASTPIN (1050 1525) BN 15
R 1
J 0
(1043 1513);
DISPLAY 0.617021 (1043 1513);
PAINT GREEN (1043 1513);
FORCEPROP 2 LAST CDS_LIB mstr_standard
J 0
(1050 1575);
PAINT ORANGE (1050 1575);
DISPLAY INVISIBLE (1050 1575);
FORCEPROP 1 LAST BODY_TYPE PLUMBING
J 0
(1100 1525);
DISPLAY 2.276596 (1100 1525);
PAINT GREEN (1100 1525);
DISPLAY INVISIBLE (1100 1525);
FORCEPROP 1 LAST HDL_TAP TRUE
J 0
(1370 1445);
DISPLAY 2.276596 (1370 1445);
PAINT GREEN (1370 1445);
DISPLAY INVISIBLE (1370 1445);
FORCEPROP 1 LAST PATH I250
J 0
(1048 1575);
DISPLAY 0.872340 (1048 1575);
PAINT GREEN (1048 1575);
DISPLAY INVISIBLE (1048 1575);
FORCEADD TAP..7
(1450 775);
FORCEPROP 3 LASTPIN (1450 825) SIG_NAME P3E_CPU0_PE1_PCH_RXN<13>
J 0
(1460 835);
DISPLAY 0.659574 (1460 835);
PAINT MONO (1460 835);
DISPLAY INVISIBLE (1460 835);
FORCEPROP 1 LASTPIN (1450 825) BN 13
R 1
J 0
(1443 773);
DISPLAY 0.617021 (1443 773);
PAINT GREEN (1443 773);
FORCEPROP 2 LAST CDS_LIB mstr_standard
J 0
(1450 775);
PAINT ORANGE (1450 775);
DISPLAY INVISIBLE (1450 775);
FORCEPROP 1 LAST BODY_TYPE PLUMBING
J 0
(1500 775);
DISPLAY 2.276596 (1500 775);
PAINT GREEN (1500 775);
DISPLAY INVISIBLE (1500 775);
FORCEPROP 1 LAST HDL_TAP TRUE
J 0
(1770 645);
DISPLAY 2.276596 (1770 645);
PAINT GREEN (1770 645);
DISPLAY INVISIBLE (1770 645);
FORCEPROP 1 LAST PATH I251
J 0
(1448 775);
DISPLAY 0.872340 (1448 775);
PAINT GREEN (1448 775);
DISPLAY INVISIBLE (1448 775);
FORCEADD TAP..7
(1650 775);
FORCEPROP 3 LASTPIN (1650 825) SIG_NAME P3E_CPU0_PE1_PCH_RXN<12>
J 0
(1660 835);
DISPLAY 0.659574 (1660 835);
PAINT MONO (1660 835);
DISPLAY INVISIBLE (1660 835);
FORCEPROP 1 LASTPIN (1650 825) BN 12
R 1
J 0
(1643 773);
DISPLAY 0.617021 (1643 773);
PAINT GREEN (1643 773);
FORCEPROP 2 LAST CDS_LIB mstr_standard
J 0
(1650 775);
PAINT ORANGE (1650 775);
DISPLAY INVISIBLE (1650 775);
FORCEPROP 1 LAST BODY_TYPE PLUMBING
J 0
(1700 775);
DISPLAY 2.276596 (1700 775);
PAINT GREEN (1700 775);
DISPLAY INVISIBLE (1700 775);
FORCEPROP 1 LAST HDL_TAP TRUE
J 0
(1970 645);
DISPLAY 2.276596 (1970 645);
PAINT GREEN (1970 645);
DISPLAY INVISIBLE (1970 645);
FORCEPROP 1 LAST PATH I252
J 0
(1648 775);
DISPLAY 0.872340 (1648 775);
PAINT GREEN (1648 775);
DISPLAY INVISIBLE (1648 775);
FORCEADD CAP..1
R 2
(1450 1025);
FORCEPROP 1 LAST LOCATION C3M14
J 2
(1400 1125);
DISPLAY 0.617021 (1400 1125);
PAINT AQUA (1400 1125);
FORCEPROP 1 LAST PART_NUMBER A36096-155
J 2
(1400 875);
DISPLAY 0.617021 (1400 875);
PAINT BLUE (1400 875);
FORCEPROP 1 LAST VALUE 0.22UF
J 2
(1400 1075);
DISPLAY 0.617021 (1400 1075);
PAINT SKYBLUE (1400 1075);
FORCEPROP 1 LAST TOLERANCE 10%
J 2
(1400 975);
DISPLAY 0.617021 (1400 975);
PAINT SKYBLUE (1400 975);
FORCEPROP 1 LAST PACK_TYPE 0402
J 2
(1400 825);
DISPLAY 0.617021 (1400 825);
PAINT SKYBLUE (1400 825);
FORCEPROP 1 LAST VOLTAGE 16V
J 2
(1400 1025);
DISPLAY 0.617021 (1400 1025);
PAINT SKYBLUE (1400 1025);
FORCEPROP 1 LAST MATERIAL X7R
J 2
(1400 925);
DISPLAY 0.617021 (1400 925);
PAINT SKYBLUE (1400 925);
FORCEPROP 1 LASTPIN (1450 925) $PN 2
J 2
(1440 905);
DISPLAY 0.617021 (1440 905);
PAINT ORANGE (1440 905);
FORCEPROP 1 LASTPIN (1450 1125) $PN 1
J 2
(1440 1105);
DISPLAY 0.617021 (1440 1105);
PAINT ORANGE (1440 1105);
FORCEPROP 2 LAST CDS_LIB mstr_discrete
J 0
(1450 1025);
PAINT ORANGE (1450 1025);
DISPLAY INVISIBLE (1450 1025);
FORCEPROP 2 LAST CDS_SEC 1
J 0
(1400 1225);
DISPLAY 1.021277 (1400 1225);
PAINT ORANGE (1400 1225);
DISPLAY INVISIBLE (1400 1225);
FORCEPROP 2 LAST $SEC 1
J 0
(1400 1225);
DISPLAY 0.680851 (1400 1225);
PAINT MONO (1400 1225);
DISPLAY INVISIBLE (1400 1225);
FORCEPROP 2 LAST CDS_LOCATION C3M14
J 2
(1400 1125);
DISPLAY 0.617021 (1400 1125);
PAINT AQUA (1400 1125);
DISPLAY INVISIBLE (1400 1125);
FORCEPROP 1 LAST PATH I253
J 2
(1400 1175);
DISPLAY 0.978723 (1400 1175);
PAINT WHITE (1400 1175);
DISPLAY INVISIBLE (1400 1175);
FORCEPROP 2 LAST ROOM OCP_STEERING
J 2
(1450 1025);
PAINT MONO (1450 1025);
DISPLAY INVISIBLE (1450 1025);
FORCEADD TAP..7
(1250 775);
FORCEPROP 3 LASTPIN (1250 825) SIG_NAME P3E_CPU0_PE1_PCH_RXN<14>
J 0
(1260 835);
DISPLAY 0.659574 (1260 835);
PAINT MONO (1260 835);
DISPLAY INVISIBLE (1260 835);
FORCEPROP 1 LASTPIN (1250 825) BN 14
R 1
J 0
(1243 773);
DISPLAY 0.617021 (1243 773);
PAINT GREEN (1243 773);
FORCEPROP 2 LAST CDS_LIB mstr_standard
J 0
(1250 775);
PAINT ORANGE (1250 775);
DISPLAY INVISIBLE (1250 775);
FORCEPROP 1 LAST BODY_TYPE PLUMBING
J 0
(1300 775);
DISPLAY 2.276596 (1300 775);
PAINT GREEN (1300 775);
DISPLAY INVISIBLE (1300 775);
FORCEPROP 1 LAST HDL_TAP TRUE
J 0
(1570 645);
DISPLAY 2.276596 (1570 645);
PAINT GREEN (1570 645);
DISPLAY INVISIBLE (1570 645);
FORCEPROP 1 LAST PATH I254
J 0
(1248 775);
DISPLAY 0.872340 (1248 775);
PAINT GREEN (1248 775);
DISPLAY INVISIBLE (1248 775);
FORCEADD CAP..1
R 2
(1050 1025);
FORCEPROP 1 LAST LOCATION C3M1
J 2
(1000 1125);
DISPLAY 0.617021 (1000 1125);
PAINT AQUA (1000 1125);
FORCEPROP 1 LAST PART_NUMBER A36096-155
J 2
(1000 875);
DISPLAY 0.617021 (1000 875);
PAINT BLUE (1000 875);
FORCEPROP 1 LAST VALUE 0.22UF
J 2
(1000 1075);
DISPLAY 0.617021 (1000 1075);
PAINT SKYBLUE (1000 1075);
FORCEPROP 1 LAST TOLERANCE 10%
J 2
(1000 975);
DISPLAY 0.617021 (1000 975);
PAINT SKYBLUE (1000 975);
FORCEPROP 1 LAST PACK_TYPE 0402
J 2
(1000 825);
DISPLAY 0.617021 (1000 825);
PAINT SKYBLUE (1000 825);
FORCEPROP 1 LAST VOLTAGE 16V
J 2
(1000 1025);
DISPLAY 0.617021 (1000 1025);
PAINT SKYBLUE (1000 1025);
FORCEPROP 1 LAST MATERIAL X7R
J 2
(1000 925);
DISPLAY 0.617021 (1000 925);
PAINT SKYBLUE (1000 925);
FORCEPROP 1 LASTPIN (1050 925) $PN 2
J 2
(1040 905);
DISPLAY 0.617021 (1040 905);
PAINT ORANGE (1040 905);
FORCEPROP 1 LASTPIN (1050 1125) $PN 1
J 2
(1040 1105);
DISPLAY 0.617021 (1040 1105);
PAINT ORANGE (1040 1105);
FORCEPROP 2 LAST CDS_LIB mstr_discrete
J 0
(1050 1025);
PAINT ORANGE (1050 1025);
DISPLAY INVISIBLE (1050 1025);
FORCEPROP 2 LAST CDS_SEC 1
J 0
(1000 1225);
DISPLAY 1.021277 (1000 1225);
PAINT ORANGE (1000 1225);
DISPLAY INVISIBLE (1000 1225);
FORCEPROP 2 LAST $SEC 1
J 0
(1000 1225);
DISPLAY 0.680851 (1000 1225);
PAINT MONO (1000 1225);
DISPLAY INVISIBLE (1000 1225);
FORCEPROP 2 LAST CDS_LOCATION C3M1
J 2
(1000 1125);
DISPLAY 0.617021 (1000 1125);
PAINT AQUA (1000 1125);
DISPLAY INVISIBLE (1000 1125);
FORCEPROP 1 LAST PATH I255
J 2
(1000 1175);
DISPLAY 0.978723 (1000 1175);
PAINT WHITE (1000 1175);
DISPLAY INVISIBLE (1000 1175);
FORCEPROP 2 LAST ROOM OCP_STEERING
J 2
(1050 1025);
PAINT MONO (1050 1025);
DISPLAY INVISIBLE (1050 1025);
FORCEADD TAP..7
(1050 775);
FORCEPROP 3 LASTPIN (1050 825) SIG_NAME P3E_CPU0_PE1_PCH_RXN<15>
J 0
(1060 835);
DISPLAY 0.659574 (1060 835);
PAINT MONO (1060 835);
DISPLAY INVISIBLE (1060 835);
FORCEPROP 1 LASTPIN (1050 825) BN 15
R 1
J 0
(1043 773);
DISPLAY 0.617021 (1043 773);
PAINT GREEN (1043 773);
FORCEPROP 2 LAST CDS_LIB mstr_standard
J 0
(1050 775);
PAINT ORANGE (1050 775);
DISPLAY INVISIBLE (1050 775);
FORCEPROP 1 LAST BODY_TYPE PLUMBING
J 0
(1100 775);
DISPLAY 2.276596 (1100 775);
PAINT GREEN (1100 775);
DISPLAY INVISIBLE (1100 775);
FORCEPROP 1 LAST HDL_TAP TRUE
J 0
(1370 645);
DISPLAY 2.276596 (1370 645);
PAINT GREEN (1370 645);
DISPLAY INVISIBLE (1370 645);
FORCEPROP 1 LAST PATH I256
J 0
(1048 775);
DISPLAY 0.872340 (1048 775);
PAINT GREEN (1048 775);
DISPLAY INVISIBLE (1048 775);
FORCEADD TAP..7
(50 4100);
FORCEPROP 3 LASTPIN (50 4150) SIG_NAME P3E_CPU0_PE2_SS_C_TXP<11>
J 0
(60 4160);
DISPLAY 0.659574 (60 4160);
PAINT MONO (60 4160);
DISPLAY INVISIBLE (60 4160);
FORCEPROP 1 LASTPIN (50 4150) BN 11
R 1
J 0
(43 4098);
DISPLAY 0.617021 (43 4098);
PAINT GREEN (43 4098);
FORCEPROP 2 LAST CDS_LIB mstr_standard
J 0
(50 4100);
PAINT ORANGE (50 4100);
DISPLAY INVISIBLE (50 4100);
FORCEPROP 1 LAST BODY_TYPE PLUMBING
J 0
(100 4100);
DISPLAY 2.276596 (100 4100);
PAINT GREEN (100 4100);
DISPLAY INVISIBLE (100 4100);
FORCEPROP 1 LAST HDL_TAP TRUE
J 0
(370 3970);
DISPLAY 2.276596 (370 3970);
PAINT GREEN (370 3970);
DISPLAY INVISIBLE (370 3970);
FORCEPROP 1 LAST PATH I26
J 0
(48 4100);
DISPLAY 0.872340 (48 4100);
PAINT GREEN (48 4100);
DISPLAY INVISIBLE (48 4100);
FORCEADD CAP..1
R 2
(-150 4650);
FORCEPROP 1 LAST LOCATION C7G11
J 2
(-200 4750);
DISPLAY 0.617021 (-200 4750);
PAINT AQUA (-200 4750);
FORCEPROP 1 LAST PART_NUMBER A36096-155
J 2
(-200 4500);
DISPLAY 0.617021 (-200 4500);
PAINT BLUE (-200 4500);
FORCEPROP 1 LAST VALUE 0.22UF
J 2
(-200 4700);
DISPLAY 0.617021 (-200 4700);
PAINT SKYBLUE (-200 4700);
FORCEPROP 1 LAST TOLERANCE 10%
J 2
(-200 4600);
DISPLAY 0.617021 (-200 4600);
PAINT SKYBLUE (-200 4600);
FORCEPROP 1 LAST PACK_TYPE 0402
J 2
(-200 4450);
DISPLAY 0.617021 (-200 4450);
PAINT SKYBLUE (-200 4450);
FORCEPROP 1 LAST VOLTAGE 16V
J 2
(-200 4650);
DISPLAY 0.617021 (-200 4650);
PAINT SKYBLUE (-200 4650);
FORCEPROP 1 LAST MATERIAL X7R
J 2
(-200 4550);
DISPLAY 0.617021 (-200 4550);
PAINT SKYBLUE (-200 4550);
FORCEPROP 1 LASTPIN (-150 4550) $PN 2
J 2
(-160 4530);
DISPLAY 0.617021 (-160 4530);
PAINT ORANGE (-160 4530);
FORCEPROP 1 LASTPIN (-150 4750) $PN 1
J 2
(-160 4730);
DISPLAY 0.617021 (-160 4730);
PAINT ORANGE (-160 4730);
FORCEPROP 2 LAST SEC_TYPE 0402
J 0
(-200 4850);
DISPLAY 1.021277 (-200 4850);
PAINT ORANGE (-200 4850);
DISPLAY INVISIBLE (-200 4850);
FORCEPROP 2 LAST CDS_LIB mstr_discrete
J 0
(-150 4650);
PAINT ORANGE (-150 4650);
DISPLAY INVISIBLE (-150 4650);
FORCEPROP 2 LAST SEC 1
J 0
(-200 4850);
DISPLAY 0.680851 (-200 4850);
PAINT MONO (-200 4850);
DISPLAY INVISIBLE (-200 4850);
FORCEPROP 2 LAST CDS_LOCATION C7G11
J 2
(-200 4750);
DISPLAY 0.617021 (-200 4750);
PAINT AQUA (-200 4750);
DISPLAY INVISIBLE (-200 4750);
FORCEPROP 1 LAST PATH I27
J 2
(-200 4800);
DISPLAY 0.978723 (-200 4800);
PAINT WHITE (-200 4800);
DISPLAY INVISIBLE (-200 4800);
FORCEPROP 2 LAST ROOM OCP_STEERING
J 2
(-150 4650);
PAINT MONO (-150 4650);
DISPLAY INVISIBLE (-150 4650);
FORCEADD CAP..1
R 2
(50 4350);
FORCEPROP 1 LAST LOCATION C7G14
J 2
(0 4450);
DISPLAY 0.617021 (0 4450);
PAINT AQUA (0 4450);
FORCEPROP 1 LAST PART_NUMBER A36096-155
J 2
(0 4200);
DISPLAY 0.617021 (0 4200);
PAINT BLUE (0 4200);
FORCEPROP 1 LAST VALUE 0.22UF
J 2
(0 4400);
DISPLAY 0.617021 (0 4400);
PAINT SKYBLUE (0 4400);
FORCEPROP 1 LAST TOLERANCE 10%
J 2
(0 4300);
DISPLAY 0.617021 (0 4300);
PAINT SKYBLUE (0 4300);
FORCEPROP 1 LAST PACK_TYPE 0402
J 2
(0 4150);
DISPLAY 0.617021 (0 4150);
PAINT SKYBLUE (0 4150);
FORCEPROP 1 LAST VOLTAGE 16V
J 2
(0 4350);
DISPLAY 0.617021 (0 4350);
PAINT SKYBLUE (0 4350);
FORCEPROP 1 LAST MATERIAL X7R
J 2
(0 4250);
DISPLAY 0.617021 (0 4250);
PAINT SKYBLUE (0 4250);
FORCEPROP 1 LASTPIN (50 4250) $PN 2
J 2
(40 4230);
DISPLAY 0.617021 (40 4230);
PAINT ORANGE (40 4230);
FORCEPROP 1 LASTPIN (50 4450) $PN 1
J 2
(40 4430);
DISPLAY 0.617021 (40 4430);
PAINT ORANGE (40 4430);
FORCEPROP 2 LAST SEC_TYPE 0402
J 0
(0 4550);
DISPLAY 1.021277 (0 4550);
PAINT ORANGE (0 4550);
DISPLAY INVISIBLE (0 4550);
FORCEPROP 2 LAST CDS_LIB mstr_discrete
J 0
(50 4350);
PAINT ORANGE (50 4350);
DISPLAY INVISIBLE (50 4350);
FORCEPROP 2 LAST SEC 1
J 0
(0 4550);
DISPLAY 0.680851 (0 4550);
PAINT MONO (0 4550);
DISPLAY INVISIBLE (0 4550);
FORCEPROP 2 LAST CDS_LOCATION C7G14
J 2
(0 4450);
DISPLAY 0.617021 (0 4450);
PAINT AQUA (0 4450);
DISPLAY INVISIBLE (0 4450);
FORCEPROP 1 LAST PATH I28
J 2
(0 4500);
DISPLAY 0.978723 (0 4500);
PAINT WHITE (0 4500);
DISPLAY INVISIBLE (0 4500);
FORCEPROP 2 LAST ROOM OCP_STEERING
J 2
(50 4350);
PAINT MONO (50 4350);
DISPLAY INVISIBLE (50 4350);
FORCEADD TAP..7
(300 3100);
FORCEPROP 3 LASTPIN (300 3150) SIG_NAME P3E_CPU0_PE2_SS_C_TXN<10>
J 0
(310 3160);
DISPLAY 0.659574 (310 3160);
PAINT MONO (310 3160);
DISPLAY INVISIBLE (310 3160);
FORCEPROP 1 LASTPIN (300 3150) BN 10
R 1
J 0
(293 3098);
DISPLAY 0.617021 (293 3098);
PAINT GREEN (293 3098);
FORCEPROP 2 LAST CDS_LIB mstr_standard
J 0
(300 3100);
PAINT ORANGE (300 3100);
DISPLAY INVISIBLE (300 3100);
FORCEPROP 1 LAST BODY_TYPE PLUMBING
J 0
(350 3100);
DISPLAY 2.276596 (350 3100);
PAINT GREEN (350 3100);
DISPLAY INVISIBLE (350 3100);
FORCEPROP 1 LAST HDL_TAP TRUE
J 0
(620 2970);
DISPLAY 2.276596 (620 2970);
PAINT GREEN (620 2970);
DISPLAY INVISIBLE (620 2970);
FORCEPROP 1 LAST PATH I29
J 0
(298 3100);
DISPLAY 0.872340 (298 3100);
PAINT GREEN (298 3100);
DISPLAY INVISIBLE (298 3100);
FORCEADD OFFPAGE..1
(-875 3950);
FORCEPROP 2 LAST $XR0 31 
J 0
(-1096 3950);
DISPLAY 0.638298 (-1096 3950);
PAINT MONO (-1096 3950);
FORCEPROP 2 LAST CDS_LIB mstr_standard
J 0
(-875 3950);
PAINT ORANGE (-875 3950);
DISPLAY INVISIBLE (-875 3950);
FORCEPROP 1 LAST OFFPAGE TRUE
J 0
(-555 3820);
PAINT GREEN (-555 3820);
DISPLAY INVISIBLE (-555 3820);
FORCEPROP 1 LAST COMMENT_BODY TRUE
J 0
(-755 3850);
DISPLAY 2.276596 (-755 3850);
PAINT GREEN (-755 3850);
DISPLAY INVISIBLE (-755 3850);
FORCEPROP 2 LAST PATH I3
J 0
(-1075 4000);
DISPLAY 1.021277 (-1075 4000);
PAINT ORANGE (-1075 4000);
DISPLAY INVISIBLE (-1075 4000);
FORCEADD TAP..7
(500 3100);
FORCEPROP 3 LASTPIN (500 3150) SIG_NAME P3E_CPU0_PE2_SS_C_TXN<9>
J 0
(510 3160);
DISPLAY 0.659574 (510 3160);
PAINT MONO (510 3160);
DISPLAY INVISIBLE (510 3160);
FORCEPROP 1 LASTPIN (500 3150) BN 9
R 1
J 0
(493 3098);
DISPLAY 0.617021 (493 3098);
PAINT GREEN (493 3098);
FORCEPROP 2 LAST CDS_LIB mstr_standard
J 0
(500 3100);
PAINT ORANGE (500 3100);
DISPLAY INVISIBLE (500 3100);
FORCEPROP 1 LAST BODY_TYPE PLUMBING
J 0
(550 3100);
DISPLAY 2.276596 (550 3100);
PAINT GREEN (550 3100);
DISPLAY INVISIBLE (550 3100);
FORCEPROP 1 LAST HDL_TAP TRUE
J 0
(820 2970);
DISPLAY 2.276596 (820 2970);
PAINT GREEN (820 2970);
DISPLAY INVISIBLE (820 2970);
FORCEPROP 1 LAST PATH I30
J 0
(498 3100);
DISPLAY 0.872340 (498 3100);
PAINT GREEN (498 3100);
DISPLAY INVISIBLE (498 3100);
FORCEADD CAP..1
R 2
(300 3650);
FORCEPROP 1 LAST LOCATION C7G16
J 2
(250 3750);
DISPLAY 0.617021 (250 3750);
PAINT AQUA (250 3750);
FORCEPROP 1 LAST PART_NUMBER A36096-155
J 2
(250 3500);
DISPLAY 0.617021 (250 3500);
PAINT BLUE (250 3500);
FORCEPROP 1 LAST VALUE 0.22UF
J 2
(250 3700);
DISPLAY 0.617021 (250 3700);
PAINT SKYBLUE (250 3700);
FORCEPROP 1 LAST TOLERANCE 10%
J 2
(250 3600);
DISPLAY 0.617021 (250 3600);
PAINT SKYBLUE (250 3600);
FORCEPROP 1 LAST PACK_TYPE 0402
J 2
(250 3450);
DISPLAY 0.617021 (250 3450);
PAINT SKYBLUE (250 3450);
FORCEPROP 1 LAST VOLTAGE 16V
J 2
(250 3650);
DISPLAY 0.617021 (250 3650);
PAINT SKYBLUE (250 3650);
FORCEPROP 1 LAST MATERIAL X7R
J 2
(250 3550);
DISPLAY 0.617021 (250 3550);
PAINT SKYBLUE (250 3550);
FORCEPROP 1 LASTPIN (300 3550) $PN 2
J 2
(290 3530);
DISPLAY 0.617021 (290 3530);
PAINT ORANGE (290 3530);
FORCEPROP 1 LASTPIN (300 3750) $PN 1
J 2
(290 3730);
DISPLAY 0.617021 (290 3730);
PAINT ORANGE (290 3730);
FORCEPROP 2 LAST SEC_TYPE 0402
J 0
(250 3850);
DISPLAY 1.021277 (250 3850);
PAINT ORANGE (250 3850);
DISPLAY INVISIBLE (250 3850);
FORCEPROP 2 LAST CDS_LIB mstr_discrete
J 0
(300 3650);
PAINT ORANGE (300 3650);
DISPLAY INVISIBLE (300 3650);
FORCEPROP 2 LAST SEC 1
J 0
(250 3850);
DISPLAY 0.680851 (250 3850);
PAINT MONO (250 3850);
DISPLAY INVISIBLE (250 3850);
FORCEPROP 2 LAST CDS_LOCATION C7G16
J 2
(250 3750);
DISPLAY 0.617021 (250 3750);
PAINT AQUA (250 3750);
DISPLAY INVISIBLE (250 3750);
FORCEPROP 1 LAST PATH I31
J 2
(250 3800);
DISPLAY 0.978723 (250 3800);
PAINT WHITE (250 3800);
DISPLAY INVISIBLE (250 3800);
FORCEPROP 2 LAST ROOM OCP_STEERING
J 2
(300 3650);
PAINT MONO (300 3650);
DISPLAY INVISIBLE (300 3650);
FORCEADD CAP..1
R 2
(500 3350);
FORCEPROP 1 LAST LOCATION C7G18
J 2
(450 3450);
DISPLAY 0.617021 (450 3450);
PAINT AQUA (450 3450);
FORCEPROP 1 LAST PART_NUMBER A36096-155
J 2
(450 3200);
DISPLAY 0.617021 (450 3200);
PAINT BLUE (450 3200);
FORCEPROP 1 LAST VALUE 0.22UF
J 2
(450 3400);
DISPLAY 0.617021 (450 3400);
PAINT SKYBLUE (450 3400);
FORCEPROP 1 LAST TOLERANCE 10%
J 2
(450 3300);
DISPLAY 0.617021 (450 3300);
PAINT SKYBLUE (450 3300);
FORCEPROP 1 LAST PACK_TYPE 0402
J 2
(450 3150);
DISPLAY 0.617021 (450 3150);
PAINT SKYBLUE (450 3150);
FORCEPROP 1 LAST VOLTAGE 16V
J 2
(450 3350);
DISPLAY 0.617021 (450 3350);
PAINT SKYBLUE (450 3350);
FORCEPROP 1 LAST MATERIAL X7R
J 2
(450 3250);
DISPLAY 0.617021 (450 3250);
PAINT SKYBLUE (450 3250);
FORCEPROP 1 LASTPIN (500 3250) $PN 2
J 2
(490 3230);
DISPLAY 0.617021 (490 3230);
PAINT ORANGE (490 3230);
FORCEPROP 1 LASTPIN (500 3450) $PN 1
J 2
(490 3430);
DISPLAY 0.617021 (490 3430);
PAINT ORANGE (490 3430);
FORCEPROP 2 LAST SEC_TYPE 0402
J 0
(450 3550);
DISPLAY 1.021277 (450 3550);
PAINT ORANGE (450 3550);
DISPLAY INVISIBLE (450 3550);
FORCEPROP 2 LAST CDS_LIB mstr_discrete
J 0
(500 3350);
PAINT ORANGE (500 3350);
DISPLAY INVISIBLE (500 3350);
FORCEPROP 2 LAST SEC 1
J 0
(450 3550);
DISPLAY 0.680851 (450 3550);
PAINT MONO (450 3550);
DISPLAY INVISIBLE (450 3550);
FORCEPROP 2 LAST CDS_LOCATION C7G18
J 2
(450 3450);
DISPLAY 0.617021 (450 3450);
PAINT AQUA (450 3450);
DISPLAY INVISIBLE (450 3450);
FORCEPROP 1 LAST PATH I32
J 2
(450 3500);
DISPLAY 0.978723 (450 3500);
PAINT WHITE (450 3500);
DISPLAY INVISIBLE (450 3500);
FORCEPROP 2 LAST ROOM OCP_STEERING
J 2
(500 3350);
PAINT MONO (500 3350);
DISPLAY INVISIBLE (500 3350);
FORCEADD TAP..7
(700 3100);
FORCEPROP 3 LASTPIN (700 3150) SIG_NAME P3E_CPU0_PE2_SS_C_TXN<8>
J 0
(710 3160);
DISPLAY 0.659574 (710 3160);
PAINT MONO (710 3160);
DISPLAY INVISIBLE (710 3160);
FORCEPROP 1 LASTPIN (700 3150) BN 8
R 1
J 0
(693 3098);
DISPLAY 0.617021 (693 3098);
PAINT GREEN (693 3098);
FORCEPROP 2 LAST CDS_LIB mstr_standard
J 0
(700 3100);
PAINT ORANGE (700 3100);
DISPLAY INVISIBLE (700 3100);
FORCEPROP 1 LAST BODY_TYPE PLUMBING
J 0
(750 3100);
DISPLAY 2.276596 (750 3100);
PAINT GREEN (750 3100);
DISPLAY INVISIBLE (750 3100);
FORCEPROP 1 LAST HDL_TAP TRUE
J 0
(1020 2970);
DISPLAY 2.276596 (1020 2970);
PAINT GREEN (1020 2970);
DISPLAY INVISIBLE (1020 2970);
FORCEPROP 1 LAST PATH I33
J 0
(698 3100);
DISPLAY 0.872340 (698 3100);
PAINT GREEN (698 3100);
DISPLAY INVISIBLE (698 3100);
FORCEADD CAP..1
R 2
(700 3650);
FORCEPROP 1 LAST LOCATION C7G20
J 2
(650 3750);
DISPLAY 0.617021 (650 3750);
PAINT AQUA (650 3750);
FORCEPROP 1 LAST PART_NUMBER A36096-155
J 2
(650 3500);
DISPLAY 0.617021 (650 3500);
PAINT BLUE (650 3500);
FORCEPROP 1 LAST VALUE 0.22UF
J 2
(650 3700);
DISPLAY 0.617021 (650 3700);
PAINT SKYBLUE (650 3700);
FORCEPROP 1 LAST TOLERANCE 10%
J 2
(650 3600);
DISPLAY 0.617021 (650 3600);
PAINT SKYBLUE (650 3600);
FORCEPROP 1 LAST PACK_TYPE 0402
J 2
(650 3450);
DISPLAY 0.617021 (650 3450);
PAINT SKYBLUE (650 3450);
FORCEPROP 1 LAST VOLTAGE 16V
J 2
(650 3650);
DISPLAY 0.617021 (650 3650);
PAINT SKYBLUE (650 3650);
FORCEPROP 1 LAST MATERIAL X7R
J 2
(650 3550);
DISPLAY 0.617021 (650 3550);
PAINT SKYBLUE (650 3550);
FORCEPROP 1 LASTPIN (700 3550) $PN 2
J 2
(690 3530);
DISPLAY 0.617021 (690 3530);
PAINT ORANGE (690 3530);
FORCEPROP 1 LASTPIN (700 3750) $PN 1
J 2
(690 3730);
DISPLAY 0.617021 (690 3730);
PAINT ORANGE (690 3730);
FORCEPROP 2 LAST SEC_TYPE 0402
J 0
(650 3850);
DISPLAY 1.021277 (650 3850);
PAINT ORANGE (650 3850);
DISPLAY INVISIBLE (650 3850);
FORCEPROP 2 LAST CDS_LIB mstr_discrete
J 0
(700 3650);
PAINT ORANGE (700 3650);
DISPLAY INVISIBLE (700 3650);
FORCEPROP 2 LAST SEC 1
J 0
(650 3850);
DISPLAY 0.680851 (650 3850);
PAINT MONO (650 3850);
DISPLAY INVISIBLE (650 3850);
FORCEPROP 2 LAST CDS_LOCATION C7G20
J 2
(650 3750);
DISPLAY 0.617021 (650 3750);
PAINT AQUA (650 3750);
DISPLAY INVISIBLE (650 3750);
FORCEPROP 1 LAST PATH I34
J 2
(650 3800);
DISPLAY 0.978723 (650 3800);
PAINT WHITE (650 3800);
DISPLAY INVISIBLE (650 3800);
FORCEPROP 2 LAST ROOM OCP_STEERING
J 2
(700 3650);
PAINT MONO (700 3650);
DISPLAY INVISIBLE (700 3650);
FORCEADD TAP..7
(925 3100);
FORCEPROP 3 LASTPIN (925 3150) SIG_NAME P3E_CPU0_PE2_SS_C_TXN<7>
J 0
(935 3160);
DISPLAY 0.659574 (935 3160);
PAINT MONO (935 3160);
DISPLAY INVISIBLE (935 3160);
FORCEPROP 1 LASTPIN (925 3150) BN 7
R 1
J 0
(918 3098);
DISPLAY 0.617021 (918 3098);
PAINT GREEN (918 3098);
FORCEPROP 2 LAST CDS_LIB mstr_standard
J 0
(925 3100);
PAINT ORANGE (925 3100);
DISPLAY INVISIBLE (925 3100);
FORCEPROP 1 LAST BODY_TYPE PLUMBING
J 0
(975 3100);
DISPLAY 2.276596 (975 3100);
PAINT GREEN (975 3100);
DISPLAY INVISIBLE (975 3100);
FORCEPROP 1 LAST HDL_TAP TRUE
J 0
(1245 2970);
DISPLAY 2.276596 (1245 2970);
PAINT GREEN (1245 2970);
DISPLAY INVISIBLE (1245 2970);
FORCEPROP 1 LAST PATH I35
J 0
(923 3100);
DISPLAY 0.872340 (923 3100);
PAINT GREEN (923 3100);
DISPLAY INVISIBLE (923 3100);
FORCEADD TAP..7
(1125 3100);
FORCEPROP 3 LASTPIN (1125 3150) SIG_NAME P3E_CPU0_PE2_SS_C_TXN<6>
J 0
(1135 3160);
DISPLAY 0.659574 (1135 3160);
PAINT MONO (1135 3160);
DISPLAY INVISIBLE (1135 3160);
FORCEPROP 1 LASTPIN (1125 3150) BN 6
R 1
J 0
(1118 3098);
DISPLAY 0.617021 (1118 3098);
PAINT GREEN (1118 3098);
FORCEPROP 2 LAST CDS_LIB mstr_standard
J 0
(1125 3100);
PAINT ORANGE (1125 3100);
DISPLAY INVISIBLE (1125 3100);
FORCEPROP 1 LAST BODY_TYPE PLUMBING
J 0
(1175 3100);
DISPLAY 2.276596 (1175 3100);
PAINT GREEN (1175 3100);
DISPLAY INVISIBLE (1175 3100);
FORCEPROP 1 LAST HDL_TAP TRUE
J 0
(1445 2970);
DISPLAY 2.276596 (1445 2970);
PAINT GREEN (1445 2970);
DISPLAY INVISIBLE (1445 2970);
FORCEPROP 1 LAST PATH I36
J 0
(1123 3100);
DISPLAY 0.872340 (1123 3100);
PAINT GREEN (1123 3100);
DISPLAY INVISIBLE (1123 3100);
FORCEADD CAP..1
R 2
(925 3350);
FORCEPROP 1 LAST LOCATION C7G22
J 2
(875 3450);
DISPLAY 0.617021 (875 3450);
PAINT AQUA (875 3450);
FORCEPROP 1 LAST PART_NUMBER A36096-155
J 2
(875 3200);
DISPLAY 0.617021 (875 3200);
PAINT BLUE (875 3200);
FORCEPROP 1 LAST VALUE 0.22UF
J 2
(875 3400);
DISPLAY 0.617021 (875 3400);
PAINT SKYBLUE (875 3400);
FORCEPROP 1 LAST TOLERANCE 10%
J 2
(875 3300);
DISPLAY 0.617021 (875 3300);
PAINT SKYBLUE (875 3300);
FORCEPROP 1 LAST PACK_TYPE 0402
J 2
(875 3150);
DISPLAY 0.617021 (875 3150);
PAINT SKYBLUE (875 3150);
FORCEPROP 1 LAST VOLTAGE 16V
J 2
(875 3350);
DISPLAY 0.617021 (875 3350);
PAINT SKYBLUE (875 3350);
FORCEPROP 1 LAST MATERIAL X7R
J 2
(875 3250);
DISPLAY 0.617021 (875 3250);
PAINT SKYBLUE (875 3250);
FORCEPROP 1 LASTPIN (925 3250) $PN 2
J 2
(915 3230);
DISPLAY 0.617021 (915 3230);
PAINT ORANGE (915 3230);
FORCEPROP 1 LASTPIN (925 3450) $PN 1
J 2
(915 3430);
DISPLAY 0.617021 (915 3430);
PAINT ORANGE (915 3430);
FORCEPROP 2 LAST CDS_LIB mstr_discrete
J 0
(925 3350);
PAINT ORANGE (925 3350);
DISPLAY INVISIBLE (925 3350);
FORCEPROP 2 LAST SEC_TYPE 0402
J 0
(875 3550);
DISPLAY 1.021277 (875 3550);
PAINT ORANGE (875 3550);
DISPLAY INVISIBLE (875 3550);
FORCEPROP 2 LAST SEC 1
J 0
(875 3550);
DISPLAY 0.680851 (875 3550);
PAINT MONO (875 3550);
DISPLAY INVISIBLE (875 3550);
FORCEPROP 2 LAST CDS_LOCATION C7G22
J 2
(875 3450);
DISPLAY 0.617021 (875 3450);
PAINT AQUA (875 3450);
DISPLAY INVISIBLE (875 3450);
FORCEPROP 1 LAST PATH I37
J 2
(875 3500);
DISPLAY 0.978723 (875 3500);
PAINT WHITE (875 3500);
DISPLAY INVISIBLE (875 3500);
FORCEPROP 2 LAST ROOM OCP_STEERING
J 2
(925 3350);
PAINT MONO (925 3350);
DISPLAY INVISIBLE (925 3350);
FORCEADD TAP..3
(300 3900);
FORCEPROP 3 LASTPIN (300 3850) SIG_NAME P3E_CPU0_PE2_SS_TXN<10>
J 0
(310 3860);
DISPLAY 0.659574 (310 3860);
PAINT MONO (310 3860);
DISPLAY INVISIBLE (310 3860);
FORCEPROP 1 LASTPIN (300 3850) BN 10
R 1
J 0
(293 3838);
DISPLAY 0.617021 (293 3838);
PAINT GREEN (293 3838);
FORCEPROP 2 LAST CDS_LIB mstr_standard
J 0
(300 3900);
PAINT ORANGE (300 3900);
DISPLAY INVISIBLE (300 3900);
FORCEPROP 1 LAST BODY_TYPE PLUMBING
J 0
(350 3850);
DISPLAY 2.276596 (350 3850);
PAINT GREEN (350 3850);
DISPLAY INVISIBLE (350 3850);
FORCEPROP 1 LAST HDL_TAP TRUE
J 0
(620 3770);
DISPLAY 2.276596 (620 3770);
PAINT GREEN (620 3770);
DISPLAY INVISIBLE (620 3770);
FORCEPROP 1 LAST PATH I38
J 0
(298 3900);
DISPLAY 0.872340 (298 3900);
PAINT GREEN (298 3900);
DISPLAY INVISIBLE (298 3900);
FORCEADD TAP..7
(250 4100);
FORCEPROP 3 LASTPIN (250 4150) SIG_NAME P3E_CPU0_PE2_SS_C_TXP<10>
J 0
(260 4160);
DISPLAY 0.659574 (260 4160);
PAINT MONO (260 4160);
DISPLAY INVISIBLE (260 4160);
FORCEPROP 1 LASTPIN (250 4150) BN 10
R 1
J 0
(243 4098);
DISPLAY 0.617021 (243 4098);
PAINT GREEN (243 4098);
FORCEPROP 2 LAST CDS_LIB mstr_standard
J 0
(250 4100);
PAINT ORANGE (250 4100);
DISPLAY INVISIBLE (250 4100);
FORCEPROP 1 LAST BODY_TYPE PLUMBING
J 0
(300 4100);
DISPLAY 2.276596 (300 4100);
PAINT GREEN (300 4100);
DISPLAY INVISIBLE (300 4100);
FORCEPROP 1 LAST HDL_TAP TRUE
J 0
(570 3970);
DISPLAY 2.276596 (570 3970);
PAINT GREEN (570 3970);
DISPLAY INVISIBLE (570 3970);
FORCEPROP 1 LAST PATH I39
J 0
(248 4100);
DISPLAY 0.872340 (248 4100);
PAINT GREEN (248 4100);
DISPLAY INVISIBLE (248 4100);
FORCEADD TAP..7
(-700 3100);
FORCEPROP 3 LASTPIN (-700 3150) SIG_NAME P3E_CPU0_PE2_SS_C_TXN<15>
J 0
(-690 3160);
DISPLAY 0.659574 (-690 3160);
PAINT MONO (-690 3160);
DISPLAY INVISIBLE (-690 3160);
FORCEPROP 1 LASTPIN (-700 3150) BN 15
R 1
J 0
(-707 3098);
DISPLAY 0.617021 (-707 3098);
PAINT GREEN (-707 3098);
FORCEPROP 2 LAST CDS_LIB mstr_standard
J 0
(-700 3100);
PAINT ORANGE (-700 3100);
DISPLAY INVISIBLE (-700 3100);
FORCEPROP 1 LAST BODY_TYPE PLUMBING
J 0
(-650 3100);
DISPLAY 2.276596 (-650 3100);
PAINT GREEN (-650 3100);
DISPLAY INVISIBLE (-650 3100);
FORCEPROP 1 LAST HDL_TAP TRUE
J 0
(-380 2970);
DISPLAY 2.276596 (-380 2970);
PAINT GREEN (-380 2970);
DISPLAY INVISIBLE (-380 2970);
FORCEPROP 1 LAST PATH I4
J 0
(-702 3100);
DISPLAY 0.872340 (-702 3100);
PAINT GREEN (-702 3100);
DISPLAY INVISIBLE (-702 3100);
FORCEADD TAP..3
(500 3900);
FORCEPROP 3 LASTPIN (500 3850) SIG_NAME P3E_CPU0_PE2_SS_TXN<9>
J 0
(510 3860);
DISPLAY 0.659574 (510 3860);
PAINT MONO (510 3860);
DISPLAY INVISIBLE (510 3860);
FORCEPROP 1 LASTPIN (500 3850) BN 9
R 1
J 0
(493 3838);
DISPLAY 0.617021 (493 3838);
PAINT GREEN (493 3838);
FORCEPROP 2 LAST CDS_LIB mstr_standard
J 0
(500 3900);
PAINT ORANGE (500 3900);
DISPLAY INVISIBLE (500 3900);
FORCEPROP 1 LAST BODY_TYPE PLUMBING
J 0
(550 3850);
DISPLAY 2.276596 (550 3850);
PAINT GREEN (550 3850);
DISPLAY INVISIBLE (550 3850);
FORCEPROP 1 LAST HDL_TAP TRUE
J 0
(820 3770);
DISPLAY 2.276596 (820 3770);
PAINT GREEN (820 3770);
DISPLAY INVISIBLE (820 3770);
FORCEPROP 1 LAST PATH I40
J 0
(498 3900);
DISPLAY 0.872340 (498 3900);
PAINT GREEN (498 3900);
DISPLAY INVISIBLE (498 3900);
FORCEADD TAP..7
(450 4100);
FORCEPROP 3 LASTPIN (450 4150) SIG_NAME P3E_CPU0_PE2_SS_C_TXP<9>
J 0
(460 4160);
DISPLAY 0.659574 (460 4160);
PAINT MONO (460 4160);
DISPLAY INVISIBLE (460 4160);
FORCEPROP 1 LASTPIN (450 4150) BN 9
R 1
J 0
(443 4098);
DISPLAY 0.617021 (443 4098);
PAINT GREEN (443 4098);
FORCEPROP 2 LAST CDS_LIB mstr_standard
J 0
(450 4100);
PAINT ORANGE (450 4100);
DISPLAY INVISIBLE (450 4100);
FORCEPROP 1 LAST BODY_TYPE PLUMBING
J 0
(500 4100);
DISPLAY 2.276596 (500 4100);
PAINT GREEN (500 4100);
DISPLAY INVISIBLE (500 4100);
FORCEPROP 1 LAST HDL_TAP TRUE
J 0
(770 3970);
DISPLAY 2.276596 (770 3970);
PAINT GREEN (770 3970);
DISPLAY INVISIBLE (770 3970);
FORCEPROP 1 LAST PATH I41
J 0
(448 4100);
DISPLAY 0.872340 (448 4100);
PAINT GREEN (448 4100);
DISPLAY INVISIBLE (448 4100);
FORCEADD TAP..3
(700 3900);
FORCEPROP 3 LASTPIN (700 3850) SIG_NAME P3E_CPU0_PE2_SS_TXN<8>
J 0
(710 3860);
DISPLAY 0.659574 (710 3860);
PAINT MONO (710 3860);
DISPLAY INVISIBLE (710 3860);
FORCEPROP 1 LASTPIN (700 3850) BN 8
R 1
J 0
(693 3838);
DISPLAY 0.617021 (693 3838);
PAINT GREEN (693 3838);
FORCEPROP 2 LAST CDS_LIB mstr_standard
J 0
(700 3900);
PAINT ORANGE (700 3900);
DISPLAY INVISIBLE (700 3900);
FORCEPROP 1 LAST BODY_TYPE PLUMBING
J 0
(750 3850);
DISPLAY 2.276596 (750 3850);
PAINT GREEN (750 3850);
DISPLAY INVISIBLE (750 3850);
FORCEPROP 1 LAST HDL_TAP TRUE
J 0
(1020 3770);
DISPLAY 2.276596 (1020 3770);
PAINT GREEN (1020 3770);
DISPLAY INVISIBLE (1020 3770);
FORCEPROP 1 LAST PATH I42
J 0
(698 3900);
DISPLAY 0.872340 (698 3900);
PAINT GREEN (698 3900);
DISPLAY INVISIBLE (698 3900);
FORCEADD TAP..7
(650 4100);
FORCEPROP 3 LASTPIN (650 4150) SIG_NAME P3E_CPU0_PE2_SS_C_TXP<8>
J 0
(660 4160);
DISPLAY 0.659574 (660 4160);
PAINT MONO (660 4160);
DISPLAY INVISIBLE (660 4160);
FORCEPROP 1 LASTPIN (650 4150) BN 8
R 1
J 0
(643 4098);
DISPLAY 0.617021 (643 4098);
PAINT GREEN (643 4098);
FORCEPROP 2 LAST CDS_LIB mstr_standard
J 0
(650 4100);
PAINT ORANGE (650 4100);
DISPLAY INVISIBLE (650 4100);
FORCEPROP 1 LAST BODY_TYPE PLUMBING
J 0
(700 4100);
DISPLAY 2.276596 (700 4100);
PAINT GREEN (700 4100);
DISPLAY INVISIBLE (700 4100);
FORCEPROP 1 LAST HDL_TAP TRUE
J 0
(970 3970);
DISPLAY 2.276596 (970 3970);
PAINT GREEN (970 3970);
DISPLAY INVISIBLE (970 3970);
FORCEPROP 1 LAST PATH I43
J 0
(648 4100);
DISPLAY 0.872340 (648 4100);
PAINT GREEN (648 4100);
DISPLAY INVISIBLE (648 4100);
FORCEADD CAP..1
R 2
(450 4350);
FORCEPROP 1 LAST LOCATION C7G17
J 2
(400 4450);
DISPLAY 0.617021 (400 4450);
PAINT AQUA (400 4450);
FORCEPROP 1 LAST PART_NUMBER A36096-155
J 2
(400 4200);
DISPLAY 0.617021 (400 4200);
PAINT BLUE (400 4200);
FORCEPROP 1 LAST VALUE 0.22UF
J 2
(400 4400);
DISPLAY 0.617021 (400 4400);
PAINT SKYBLUE (400 4400);
FORCEPROP 1 LAST TOLERANCE 10%
J 2
(400 4300);
DISPLAY 0.617021 (400 4300);
PAINT SKYBLUE (400 4300);
FORCEPROP 1 LAST PACK_TYPE 0402
J 2
(400 4150);
DISPLAY 0.617021 (400 4150);
PAINT SKYBLUE (400 4150);
FORCEPROP 1 LAST VOLTAGE 16V
J 2
(400 4350);
DISPLAY 0.617021 (400 4350);
PAINT SKYBLUE (400 4350);
FORCEPROP 1 LAST MATERIAL X7R
J 2
(400 4250);
DISPLAY 0.617021 (400 4250);
PAINT SKYBLUE (400 4250);
FORCEPROP 1 LASTPIN (450 4250) $PN 2
J 2
(440 4230);
DISPLAY 0.617021 (440 4230);
PAINT ORANGE (440 4230);
FORCEPROP 1 LASTPIN (450 4450) $PN 1
J 2
(440 4430);
DISPLAY 0.617021 (440 4430);
PAINT ORANGE (440 4430);
FORCEPROP 2 LAST SEC_TYPE 0402
J 0
(400 4550);
DISPLAY 1.021277 (400 4550);
PAINT ORANGE (400 4550);
DISPLAY INVISIBLE (400 4550);
FORCEPROP 2 LAST CDS_LIB mstr_discrete
J 0
(450 4350);
PAINT ORANGE (450 4350);
DISPLAY INVISIBLE (450 4350);
FORCEPROP 2 LAST SEC 1
J 0
(400 4550);
DISPLAY 0.680851 (400 4550);
PAINT MONO (400 4550);
DISPLAY INVISIBLE (400 4550);
FORCEPROP 2 LAST CDS_LOCATION C7G17
J 2
(400 4450);
DISPLAY 0.617021 (400 4450);
PAINT AQUA (400 4450);
DISPLAY INVISIBLE (400 4450);
FORCEPROP 1 LAST PATH I44
J 2
(400 4500);
DISPLAY 0.978723 (400 4500);
PAINT WHITE (400 4500);
DISPLAY INVISIBLE (400 4500);
FORCEPROP 2 LAST ROOM OCP_STEERING
J 2
(450 4350);
PAINT MONO (450 4350);
DISPLAY INVISIBLE (450 4350);
FORCEADD CAP..1
R 2
(250 4650);
FORCEPROP 1 LAST LOCATION C7G15
J 2
(200 4750);
DISPLAY 0.617021 (200 4750);
PAINT AQUA (200 4750);
FORCEPROP 1 LAST PART_NUMBER A36096-155
J 2
(200 4500);
DISPLAY 0.617021 (200 4500);
PAINT BLUE (200 4500);
FORCEPROP 1 LAST VALUE 0.22UF
J 2
(200 4700);
DISPLAY 0.617021 (200 4700);
PAINT SKYBLUE (200 4700);
FORCEPROP 1 LAST TOLERANCE 10%
J 2
(200 4600);
DISPLAY 0.617021 (200 4600);
PAINT SKYBLUE (200 4600);
FORCEPROP 1 LAST PACK_TYPE 0402
J 2
(200 4450);
DISPLAY 0.617021 (200 4450);
PAINT SKYBLUE (200 4450);
FORCEPROP 1 LAST VOLTAGE 16V
J 2
(200 4650);
DISPLAY 0.617021 (200 4650);
PAINT SKYBLUE (200 4650);
FORCEPROP 1 LAST MATERIAL X7R
J 2
(200 4550);
DISPLAY 0.617021 (200 4550);
PAINT SKYBLUE (200 4550);
FORCEPROP 1 LASTPIN (250 4550) $PN 2
J 2
(240 4530);
DISPLAY 0.617021 (240 4530);
PAINT ORANGE (240 4530);
FORCEPROP 1 LASTPIN (250 4750) $PN 1
J 2
(240 4730);
DISPLAY 0.617021 (240 4730);
PAINT ORANGE (240 4730);
FORCEPROP 2 LAST SEC_TYPE 0402
J 0
(200 4850);
DISPLAY 1.021277 (200 4850);
PAINT ORANGE (200 4850);
DISPLAY INVISIBLE (200 4850);
FORCEPROP 2 LAST CDS_LIB mstr_discrete
J 0
(250 4650);
PAINT ORANGE (250 4650);
DISPLAY INVISIBLE (250 4650);
FORCEPROP 2 LAST SEC 1
J 0
(200 4850);
DISPLAY 0.680851 (200 4850);
PAINT MONO (200 4850);
DISPLAY INVISIBLE (200 4850);
FORCEPROP 2 LAST CDS_LOCATION C7G15
J 2
(200 4750);
DISPLAY 0.617021 (200 4750);
PAINT AQUA (200 4750);
DISPLAY INVISIBLE (200 4750);
FORCEPROP 1 LAST PATH I45
J 2
(200 4800);
DISPLAY 0.978723 (200 4800);
PAINT WHITE (200 4800);
DISPLAY INVISIBLE (200 4800);
FORCEPROP 2 LAST ROOM OCP_STEERING
J 2
(250 4650);
PAINT MONO (250 4650);
DISPLAY INVISIBLE (250 4650);
FORCEADD CAP..1
R 2
(650 4650);
FORCEPROP 1 LAST LOCATION C7G19
J 2
(600 4750);
DISPLAY 0.617021 (600 4750);
PAINT AQUA (600 4750);
FORCEPROP 1 LAST PART_NUMBER A36096-155
J 2
(600 4500);
DISPLAY 0.617021 (600 4500);
PAINT BLUE (600 4500);
FORCEPROP 1 LAST VALUE 0.22UF
J 2
(600 4700);
DISPLAY 0.617021 (600 4700);
PAINT SKYBLUE (600 4700);
FORCEPROP 1 LAST TOLERANCE 10%
J 2
(600 4600);
DISPLAY 0.617021 (600 4600);
PAINT SKYBLUE (600 4600);
FORCEPROP 1 LAST PACK_TYPE 0402
J 2
(600 4450);
DISPLAY 0.617021 (600 4450);
PAINT SKYBLUE (600 4450);
FORCEPROP 1 LAST VOLTAGE 16V
J 2
(600 4650);
DISPLAY 0.617021 (600 4650);
PAINT SKYBLUE (600 4650);
FORCEPROP 1 LAST MATERIAL X7R
J 2
(600 4550);
DISPLAY 0.617021 (600 4550);
PAINT SKYBLUE (600 4550);
FORCEPROP 1 LASTPIN (650 4550) $PN 2
J 2
(640 4530);
DISPLAY 0.617021 (640 4530);
PAINT ORANGE (640 4530);
FORCEPROP 1 LASTPIN (650 4750) $PN 1
J 2
(640 4730);
DISPLAY 0.617021 (640 4730);
PAINT ORANGE (640 4730);
FORCEPROP 2 LAST SEC_TYPE 0402
J 0
(600 4850);
DISPLAY 1.021277 (600 4850);
PAINT ORANGE (600 4850);
DISPLAY INVISIBLE (600 4850);
FORCEPROP 2 LAST CDS_LIB mstr_discrete
J 0
(650 4650);
PAINT ORANGE (650 4650);
DISPLAY INVISIBLE (650 4650);
FORCEPROP 2 LAST SEC 1
J 0
(600 4850);
DISPLAY 0.680851 (600 4850);
PAINT MONO (600 4850);
DISPLAY INVISIBLE (600 4850);
FORCEPROP 2 LAST CDS_LOCATION C7G19
J 2
(600 4750);
DISPLAY 0.617021 (600 4750);
PAINT AQUA (600 4750);
DISPLAY INVISIBLE (600 4750);
FORCEPROP 1 LAST PATH I46
J 2
(600 4800);
DISPLAY 0.978723 (600 4800);
PAINT WHITE (600 4800);
DISPLAY INVISIBLE (600 4800);
FORCEPROP 2 LAST ROOM OCP_STEERING
J 2
(650 4650);
PAINT MONO (650 4650);
DISPLAY INVISIBLE (650 4650);
FORCEADD TAP..3
(925 3900);
FORCEPROP 3 LASTPIN (925 3850) SIG_NAME P3E_CPU0_PE2_SS_TXN<7>
J 0
(935 3860);
DISPLAY 0.659574 (935 3860);
PAINT MONO (935 3860);
DISPLAY INVISIBLE (935 3860);
FORCEPROP 1 LASTPIN (925 3850) BN 7
R 1
J 0
(918 3838);
DISPLAY 0.617021 (918 3838);
PAINT GREEN (918 3838);
FORCEPROP 2 LAST CDS_LIB mstr_standard
J 0
(925 3900);
PAINT ORANGE (925 3900);
DISPLAY INVISIBLE (925 3900);
FORCEPROP 1 LAST BODY_TYPE PLUMBING
J 0
(975 3850);
DISPLAY 2.276596 (975 3850);
PAINT GREEN (975 3850);
DISPLAY INVISIBLE (975 3850);
FORCEPROP 1 LAST HDL_TAP TRUE
J 0
(1245 3770);
DISPLAY 2.276596 (1245 3770);
PAINT GREEN (1245 3770);
DISPLAY INVISIBLE (1245 3770);
FORCEPROP 1 LAST PATH I47
J 0
(923 3900);
DISPLAY 0.872340 (923 3900);
PAINT GREEN (923 3900);
DISPLAY INVISIBLE (923 3900);
FORCEADD TAP..7
(875 4100);
FORCEPROP 3 LASTPIN (875 4150) SIG_NAME P3E_CPU0_PE2_SS_C_TXP<7>
J 0
(885 4160);
DISPLAY 0.659574 (885 4160);
PAINT MONO (885 4160);
DISPLAY INVISIBLE (885 4160);
FORCEPROP 1 LASTPIN (875 4150) BN 7
R 1
J 0
(868 4098);
DISPLAY 0.617021 (868 4098);
PAINT GREEN (868 4098);
FORCEPROP 2 LAST CDS_LIB mstr_standard
J 0
(875 4100);
PAINT ORANGE (875 4100);
DISPLAY INVISIBLE (875 4100);
FORCEPROP 1 LAST BODY_TYPE PLUMBING
J 0
(925 4100);
DISPLAY 2.276596 (925 4100);
PAINT GREEN (925 4100);
DISPLAY INVISIBLE (925 4100);
FORCEPROP 1 LAST HDL_TAP TRUE
J 0
(1195 3970);
DISPLAY 2.276596 (1195 3970);
PAINT GREEN (1195 3970);
DISPLAY INVISIBLE (1195 3970);
FORCEPROP 1 LAST PATH I48
J 0
(873 4100);
DISPLAY 0.872340 (873 4100);
PAINT GREEN (873 4100);
DISPLAY INVISIBLE (873 4100);
FORCEADD TAP..7
(1075 4100);
FORCEPROP 3 LASTPIN (1075 4150) SIG_NAME P3E_CPU0_PE2_SS_C_TXP<6>
J 0
(1085 4160);
DISPLAY 0.659574 (1085 4160);
PAINT MONO (1085 4160);
DISPLAY INVISIBLE (1085 4160);
FORCEPROP 1 LASTPIN (1075 4150) BN 6
R 1
J 0
(1068 4098);
DISPLAY 0.617021 (1068 4098);
PAINT GREEN (1068 4098);
FORCEPROP 2 LAST CDS_LIB mstr_standard
J 0
(1075 4100);
PAINT ORANGE (1075 4100);
DISPLAY INVISIBLE (1075 4100);
FORCEPROP 1 LAST BODY_TYPE PLUMBING
J 0
(1125 4100);
DISPLAY 2.276596 (1125 4100);
PAINT GREEN (1125 4100);
DISPLAY INVISIBLE (1125 4100);
FORCEPROP 1 LAST HDL_TAP TRUE
J 0
(1395 3970);
DISPLAY 2.276596 (1395 3970);
PAINT GREEN (1395 3970);
DISPLAY INVISIBLE (1395 3970);
FORCEPROP 1 LAST PATH I49
J 0
(1073 4100);
DISPLAY 0.872340 (1073 4100);
PAINT GREEN (1073 4100);
DISPLAY INVISIBLE (1073 4100);
FORCEADD TAP..7
(-500 3100);
FORCEPROP 3 LASTPIN (-500 3150) SIG_NAME P3E_CPU0_PE2_SS_C_TXN<14>
J 0
(-490 3160);
DISPLAY 0.659574 (-490 3160);
PAINT MONO (-490 3160);
DISPLAY INVISIBLE (-490 3160);
FORCEPROP 1 LASTPIN (-500 3150) BN 14
R 1
J 0
(-507 3098);
DISPLAY 0.617021 (-507 3098);
PAINT GREEN (-507 3098);
FORCEPROP 2 LAST CDS_LIB mstr_standard
J 0
(-500 3100);
PAINT ORANGE (-500 3100);
DISPLAY INVISIBLE (-500 3100);
FORCEPROP 1 LAST BODY_TYPE PLUMBING
J 0
(-450 3100);
DISPLAY 2.276596 (-450 3100);
PAINT GREEN (-450 3100);
DISPLAY INVISIBLE (-450 3100);
FORCEPROP 1 LAST HDL_TAP TRUE
J 0
(-180 2970);
DISPLAY 2.276596 (-180 2970);
PAINT GREEN (-180 2970);
DISPLAY INVISIBLE (-180 2970);
FORCEPROP 1 LAST PATH I5
J 0
(-502 3100);
DISPLAY 0.872340 (-502 3100);
PAINT GREEN (-502 3100);
DISPLAY INVISIBLE (-502 3100);
FORCEADD TAP..3
(1125 3900);
FORCEPROP 3 LASTPIN (1125 3850) SIG_NAME P3E_CPU0_PE2_SS_TXN<6>
J 0
(1135 3860);
DISPLAY 0.659574 (1135 3860);
PAINT MONO (1135 3860);
DISPLAY INVISIBLE (1135 3860);
FORCEPROP 1 LASTPIN (1125 3850) BN 6
R 1
J 0
(1118 3838);
DISPLAY 0.617021 (1118 3838);
PAINT GREEN (1118 3838);
FORCEPROP 2 LAST CDS_LIB mstr_standard
J 0
(1125 3900);
PAINT ORANGE (1125 3900);
DISPLAY INVISIBLE (1125 3900);
FORCEPROP 1 LAST BODY_TYPE PLUMBING
J 0
(1175 3850);
DISPLAY 2.276596 (1175 3850);
PAINT GREEN (1175 3850);
DISPLAY INVISIBLE (1175 3850);
FORCEPROP 1 LAST HDL_TAP TRUE
J 0
(1445 3770);
DISPLAY 2.276596 (1445 3770);
PAINT GREEN (1445 3770);
DISPLAY INVISIBLE (1445 3770);
FORCEPROP 1 LAST PATH I50
J 0
(1123 3900);
DISPLAY 0.872340 (1123 3900);
PAINT GREEN (1123 3900);
DISPLAY INVISIBLE (1123 3900);
FORCEADD CAP..1
R 2
(875 4350);
FORCEPROP 1 LAST LOCATION C7G21
J 2
(825 4450);
DISPLAY 0.617021 (825 4450);
PAINT AQUA (825 4450);
FORCEPROP 1 LAST PART_NUMBER A36096-155
J 2
(825 4200);
DISPLAY 0.617021 (825 4200);
PAINT BLUE (825 4200);
FORCEPROP 1 LAST VALUE 0.22UF
J 2
(825 4400);
DISPLAY 0.617021 (825 4400);
PAINT SKYBLUE (825 4400);
FORCEPROP 1 LAST TOLERANCE 10%
J 2
(825 4300);
DISPLAY 0.617021 (825 4300);
PAINT SKYBLUE (825 4300);
FORCEPROP 1 LAST PACK_TYPE 0402
J 2
(825 4150);
DISPLAY 0.617021 (825 4150);
PAINT SKYBLUE (825 4150);
FORCEPROP 1 LAST VOLTAGE 16V
J 2
(825 4350);
DISPLAY 0.617021 (825 4350);
PAINT SKYBLUE (825 4350);
FORCEPROP 1 LAST MATERIAL X7R
J 2
(825 4250);
DISPLAY 0.617021 (825 4250);
PAINT SKYBLUE (825 4250);
FORCEPROP 1 LASTPIN (875 4250) $PN 2
J 2
(865 4230);
DISPLAY 0.617021 (865 4230);
PAINT ORANGE (865 4230);
FORCEPROP 1 LASTPIN (875 4450) $PN 1
J 2
(865 4430);
DISPLAY 0.617021 (865 4430);
PAINT ORANGE (865 4430);
FORCEPROP 2 LAST CDS_LIB mstr_discrete
J 0
(875 4350);
PAINT ORANGE (875 4350);
DISPLAY INVISIBLE (875 4350);
FORCEPROP 2 LAST SEC_TYPE 0402
J 0
(825 4550);
DISPLAY 1.021277 (825 4550);
PAINT ORANGE (825 4550);
DISPLAY INVISIBLE (825 4550);
FORCEPROP 2 LAST SEC 1
J 0
(825 4550);
DISPLAY 0.680851 (825 4550);
PAINT MONO (825 4550);
DISPLAY INVISIBLE (825 4550);
FORCEPROP 2 LAST CDS_LOCATION C7G21
J 2
(825 4450);
DISPLAY 0.617021 (825 4450);
PAINT AQUA (825 4450);
DISPLAY INVISIBLE (825 4450);
FORCEPROP 1 LAST PATH I51
J 2
(825 4500);
DISPLAY 0.978723 (825 4500);
PAINT WHITE (825 4500);
DISPLAY INVISIBLE (825 4500);
FORCEPROP 2 LAST ROOM OCP_STEERING
J 2
(875 4350);
PAINT MONO (875 4350);
DISPLAY INVISIBLE (875 4350);
FORCEADD CAP..1
R 2
(1075 4650);
FORCEPROP 1 LAST LOCATION C7G23
J 2
(1025 4750);
DISPLAY 0.617021 (1025 4750);
PAINT AQUA (1025 4750);
FORCEPROP 1 LAST PART_NUMBER A36096-155
J 2
(1025 4500);
DISPLAY 0.617021 (1025 4500);
PAINT BLUE (1025 4500);
FORCEPROP 1 LAST VALUE 0.22UF
J 2
(1025 4700);
DISPLAY 0.617021 (1025 4700);
PAINT SKYBLUE (1025 4700);
FORCEPROP 1 LAST TOLERANCE 10%
J 2
(1025 4600);
DISPLAY 0.617021 (1025 4600);
PAINT SKYBLUE (1025 4600);
FORCEPROP 1 LAST PACK_TYPE 0402
J 2
(1025 4450);
DISPLAY 0.617021 (1025 4450);
PAINT SKYBLUE (1025 4450);
FORCEPROP 1 LAST VOLTAGE 16V
J 2
(1025 4650);
DISPLAY 0.617021 (1025 4650);
PAINT SKYBLUE (1025 4650);
FORCEPROP 1 LAST MATERIAL X7R
J 2
(1025 4550);
DISPLAY 0.617021 (1025 4550);
PAINT SKYBLUE (1025 4550);
FORCEPROP 1 LASTPIN (1075 4550) $PN 2
J 2
(1065 4530);
DISPLAY 0.617021 (1065 4530);
PAINT ORANGE (1065 4530);
FORCEPROP 1 LASTPIN (1075 4750) $PN 1
J 2
(1065 4730);
DISPLAY 0.617021 (1065 4730);
PAINT ORANGE (1065 4730);
FORCEPROP 2 LAST CDS_LIB mstr_discrete
J 0
(1075 4650);
PAINT ORANGE (1075 4650);
DISPLAY INVISIBLE (1075 4650);
FORCEPROP 2 LAST SEC_TYPE 0402
J 0
(1025 4850);
DISPLAY 1.021277 (1025 4850);
PAINT ORANGE (1025 4850);
DISPLAY INVISIBLE (1025 4850);
FORCEPROP 2 LAST SEC 1
J 0
(1025 4850);
DISPLAY 0.680851 (1025 4850);
PAINT MONO (1025 4850);
DISPLAY INVISIBLE (1025 4850);
FORCEPROP 2 LAST CDS_LOCATION C7G23
J 2
(1025 4750);
DISPLAY 0.617021 (1025 4750);
PAINT AQUA (1025 4750);
DISPLAY INVISIBLE (1025 4750);
FORCEPROP 1 LAST PATH I52
J 2
(1025 4800);
DISPLAY 0.978723 (1025 4800);
PAINT WHITE (1025 4800);
DISPLAY INVISIBLE (1025 4800);
FORCEPROP 2 LAST ROOM OCP_STEERING
J 2
(1075 4650);
PAINT MONO (1075 4650);
DISPLAY INVISIBLE (1075 4650);
FORCEADD TAP..7
(1525 3100);
FORCEPROP 3 LASTPIN (1525 3150) SIG_NAME P3E_CPU0_PE2_SS_C_TXN<4>
J 0
(1535 3160);
DISPLAY 0.659574 (1535 3160);
PAINT MONO (1535 3160);
DISPLAY INVISIBLE (1535 3160);
FORCEPROP 1 LASTPIN (1525 3150) BN 4
R 1
J 0
(1518 3098);
DISPLAY 0.617021 (1518 3098);
PAINT GREEN (1518 3098);
FORCEPROP 2 LAST CDS_LIB mstr_standard
J 0
(1525 3100);
PAINT ORANGE (1525 3100);
DISPLAY INVISIBLE (1525 3100);
FORCEPROP 1 LAST BODY_TYPE PLUMBING
J 0
(1575 3100);
DISPLAY 2.276596 (1575 3100);
PAINT GREEN (1575 3100);
DISPLAY INVISIBLE (1575 3100);
FORCEPROP 1 LAST HDL_TAP TRUE
J 0
(1845 2970);
DISPLAY 2.276596 (1845 2970);
PAINT GREEN (1845 2970);
DISPLAY INVISIBLE (1845 2970);
FORCEPROP 1 LAST PATH I53
J 0
(1523 3100);
DISPLAY 0.872340 (1523 3100);
PAINT GREEN (1523 3100);
DISPLAY INVISIBLE (1523 3100);
FORCEADD TAP..7
(1325 3100);
FORCEPROP 3 LASTPIN (1325 3150) SIG_NAME P3E_CPU0_PE2_SS_C_TXN<5>
J 0
(1335 3160);
DISPLAY 0.659574 (1335 3160);
PAINT MONO (1335 3160);
DISPLAY INVISIBLE (1335 3160);
FORCEPROP 1 LASTPIN (1325 3150) BN 5
R 1
J 0
(1318 3098);
DISPLAY 0.617021 (1318 3098);
PAINT GREEN (1318 3098);
FORCEPROP 2 LAST CDS_LIB mstr_standard
J 0
(1325 3100);
PAINT ORANGE (1325 3100);
DISPLAY INVISIBLE (1325 3100);
FORCEPROP 1 LAST BODY_TYPE PLUMBING
J 0
(1375 3100);
DISPLAY 2.276596 (1375 3100);
PAINT GREEN (1375 3100);
DISPLAY INVISIBLE (1375 3100);
FORCEPROP 1 LAST HDL_TAP TRUE
J 0
(1645 2970);
DISPLAY 2.276596 (1645 2970);
PAINT GREEN (1645 2970);
DISPLAY INVISIBLE (1645 2970);
FORCEPROP 1 LAST PATH I54
J 0
(1323 3100);
DISPLAY 0.872340 (1323 3100);
PAINT GREEN (1323 3100);
DISPLAY INVISIBLE (1323 3100);
FORCEADD CAP..1
R 2
(1325 3350);
FORCEPROP 1 LAST LOCATION C7G26
J 2
(1275 3450);
DISPLAY 0.617021 (1275 3450);
PAINT AQUA (1275 3450);
FORCEPROP 1 LAST PART_NUMBER A36096-155
J 2
(1275 3200);
DISPLAY 0.617021 (1275 3200);
PAINT BLUE (1275 3200);
FORCEPROP 1 LAST VALUE 0.22UF
J 2
(1275 3400);
DISPLAY 0.617021 (1275 3400);
PAINT SKYBLUE (1275 3400);
FORCEPROP 1 LAST TOLERANCE 10%
J 2
(1275 3300);
DISPLAY 0.617021 (1275 3300);
PAINT SKYBLUE (1275 3300);
FORCEPROP 1 LAST PACK_TYPE 0402
J 2
(1275 3150);
DISPLAY 0.617021 (1275 3150);
PAINT SKYBLUE (1275 3150);
FORCEPROP 1 LAST VOLTAGE 16V
J 2
(1275 3350);
DISPLAY 0.617021 (1275 3350);
PAINT SKYBLUE (1275 3350);
FORCEPROP 1 LAST MATERIAL X7R
J 2
(1275 3250);
DISPLAY 0.617021 (1275 3250);
PAINT SKYBLUE (1275 3250);
FORCEPROP 1 LASTPIN (1325 3250) $PN 2
J 2
(1315 3230);
DISPLAY 0.617021 (1315 3230);
PAINT ORANGE (1315 3230);
FORCEPROP 1 LASTPIN (1325 3450) $PN 1
J 2
(1315 3430);
DISPLAY 0.617021 (1315 3430);
PAINT ORANGE (1315 3430);
FORCEPROP 2 LAST CDS_LIB mstr_discrete
J 0
(1325 3350);
PAINT ORANGE (1325 3350);
DISPLAY INVISIBLE (1325 3350);
FORCEPROP 2 LAST SEC_TYPE 0402
J 0
(1275 3550);
DISPLAY 1.021277 (1275 3550);
PAINT ORANGE (1275 3550);
DISPLAY INVISIBLE (1275 3550);
FORCEPROP 2 LAST SEC 1
J 0
(1275 3550);
DISPLAY 0.680851 (1275 3550);
PAINT MONO (1275 3550);
DISPLAY INVISIBLE (1275 3550);
FORCEPROP 2 LAST CDS_LOCATION C7G26
J 2
(1275 3450);
DISPLAY 0.617021 (1275 3450);
PAINT AQUA (1275 3450);
DISPLAY INVISIBLE (1275 3450);
FORCEPROP 1 LAST PATH I55
J 2
(1275 3500);
DISPLAY 0.978723 (1275 3500);
PAINT WHITE (1275 3500);
DISPLAY INVISIBLE (1275 3500);
FORCEPROP 2 LAST ROOM OCP_STEERING
J 2
(1325 3350);
PAINT MONO (1325 3350);
DISPLAY INVISIBLE (1325 3350);
FORCEADD CAP..1
R 2
(1725 3350);
FORCEPROP 1 LAST LOCATION C8G4
J 2
(1675 3450);
DISPLAY 0.617021 (1675 3450);
PAINT AQUA (1675 3450);
FORCEPROP 1 LAST PART_NUMBER A36096-155
J 2
(1675 3200);
DISPLAY 0.617021 (1675 3200);
PAINT BLUE (1675 3200);
FORCEPROP 1 LAST VALUE 0.22UF
J 2
(1675 3400);
DISPLAY 0.617021 (1675 3400);
PAINT SKYBLUE (1675 3400);
FORCEPROP 1 LAST TOLERANCE 10%
J 2
(1675 3300);
DISPLAY 0.617021 (1675 3300);
PAINT SKYBLUE (1675 3300);
FORCEPROP 1 LAST PACK_TYPE 0402
J 2
(1675 3150);
DISPLAY 0.617021 (1675 3150);
PAINT SKYBLUE (1675 3150);
FORCEPROP 1 LAST VOLTAGE 16V
J 2
(1675 3350);
DISPLAY 0.617021 (1675 3350);
PAINT SKYBLUE (1675 3350);
FORCEPROP 1 LAST MATERIAL X7R
J 2
(1675 3250);
DISPLAY 0.617021 (1675 3250);
PAINT SKYBLUE (1675 3250);
FORCEPROP 1 LASTPIN (1725 3250) $PN 2
J 2
(1715 3230);
DISPLAY 0.617021 (1715 3230);
PAINT ORANGE (1715 3230);
FORCEPROP 1 LASTPIN (1725 3450) $PN 1
J 2
(1715 3430);
DISPLAY 0.617021 (1715 3430);
PAINT ORANGE (1715 3430);
FORCEPROP 2 LAST CDS_LIB mstr_discrete
J 0
(1725 3350);
PAINT ORANGE (1725 3350);
DISPLAY INVISIBLE (1725 3350);
FORCEPROP 2 LAST SEC_TYPE 0402
J 0
(1675 3550);
DISPLAY 1.021277 (1675 3550);
PAINT ORANGE (1675 3550);
DISPLAY INVISIBLE (1675 3550);
FORCEPROP 2 LAST SEC 1
J 0
(1675 3550);
DISPLAY 0.680851 (1675 3550);
PAINT MONO (1675 3550);
DISPLAY INVISIBLE (1675 3550);
FORCEPROP 2 LAST CDS_LOCATION C8G4
J 2
(1675 3450);
DISPLAY 0.617021 (1675 3450);
PAINT AQUA (1675 3450);
DISPLAY INVISIBLE (1675 3450);
FORCEPROP 1 LAST PATH I56
J 2
(1675 3500);
DISPLAY 0.978723 (1675 3500);
PAINT WHITE (1675 3500);
DISPLAY INVISIBLE (1675 3500);
FORCEPROP 2 LAST ROOM OCP_STEERING
J 2
(1725 3350);
PAINT MONO (1725 3350);
DISPLAY INVISIBLE (1725 3350);
FORCEADD TAP..7
(1725 3100);
FORCEPROP 3 LASTPIN (1725 3150) SIG_NAME P3E_CPU0_PE2_SS_C_TXN<3>
J 0
(1735 3160);
DISPLAY 0.659574 (1735 3160);
PAINT MONO (1735 3160);
DISPLAY INVISIBLE (1735 3160);
FORCEPROP 1 LASTPIN (1725 3150) BN 3
R 1
J 0
(1718 3098);
DISPLAY 0.617021 (1718 3098);
PAINT GREEN (1718 3098);
FORCEPROP 2 LAST CDS_LIB mstr_standard
J 0
(1725 3100);
PAINT ORANGE (1725 3100);
DISPLAY INVISIBLE (1725 3100);
FORCEPROP 1 LAST BODY_TYPE PLUMBING
J 0
(1775 3100);
DISPLAY 2.276596 (1775 3100);
PAINT GREEN (1775 3100);
DISPLAY INVISIBLE (1775 3100);
FORCEPROP 1 LAST HDL_TAP TRUE
J 0
(2045 2970);
DISPLAY 2.276596 (2045 2970);
PAINT GREEN (2045 2970);
DISPLAY INVISIBLE (2045 2970);
FORCEPROP 1 LAST PATH I57
J 0
(1723 3100);
DISPLAY 0.872340 (1723 3100);
PAINT GREEN (1723 3100);
DISPLAY INVISIBLE (1723 3100);
FORCEADD CAP..1
R 2
(1525 3650);
FORCEPROP 1 LAST LOCATION C8G2
J 2
(1475 3750);
DISPLAY 0.617021 (1475 3750);
PAINT AQUA (1475 3750);
FORCEPROP 1 LAST PART_NUMBER A36096-155
J 2
(1475 3500);
DISPLAY 0.617021 (1475 3500);
PAINT BLUE (1475 3500);
FORCEPROP 1 LAST VALUE 0.22UF
J 2
(1475 3700);
DISPLAY 0.617021 (1475 3700);
PAINT SKYBLUE (1475 3700);
FORCEPROP 1 LAST TOLERANCE 10%
J 2
(1475 3600);
DISPLAY 0.617021 (1475 3600);
PAINT SKYBLUE (1475 3600);
FORCEPROP 1 LAST PACK_TYPE 0402
J 2
(1475 3450);
DISPLAY 0.617021 (1475 3450);
PAINT SKYBLUE (1475 3450);
FORCEPROP 1 LAST VOLTAGE 16V
J 2
(1475 3650);
DISPLAY 0.617021 (1475 3650);
PAINT SKYBLUE (1475 3650);
FORCEPROP 1 LAST MATERIAL X7R
J 2
(1475 3550);
DISPLAY 0.617021 (1475 3550);
PAINT SKYBLUE (1475 3550);
FORCEPROP 1 LASTPIN (1525 3550) $PN 2
J 2
(1515 3530);
DISPLAY 0.617021 (1515 3530);
PAINT ORANGE (1515 3530);
FORCEPROP 1 LASTPIN (1525 3750) $PN 1
J 2
(1515 3730);
DISPLAY 0.617021 (1515 3730);
PAINT ORANGE (1515 3730);
FORCEPROP 2 LAST CDS_LIB mstr_discrete
J 0
(1525 3650);
PAINT ORANGE (1525 3650);
DISPLAY INVISIBLE (1525 3650);
FORCEPROP 2 LAST SEC_TYPE 0402
J 0
(1475 3850);
DISPLAY 1.021277 (1475 3850);
PAINT ORANGE (1475 3850);
DISPLAY INVISIBLE (1475 3850);
FORCEPROP 2 LAST SEC 1
J 0
(1475 3850);
DISPLAY 0.680851 (1475 3850);
PAINT MONO (1475 3850);
DISPLAY INVISIBLE (1475 3850);
FORCEPROP 2 LAST CDS_LOCATION C8G2
J 2
(1475 3750);
DISPLAY 0.617021 (1475 3750);
PAINT AQUA (1475 3750);
DISPLAY INVISIBLE (1475 3750);
FORCEPROP 1 LAST PATH I58
J 2
(1475 3800);
DISPLAY 0.978723 (1475 3800);
PAINT WHITE (1475 3800);
DISPLAY INVISIBLE (1475 3800);
FORCEPROP 2 LAST ROOM OCP_STEERING
J 2
(1525 3650);
PAINT MONO (1525 3650);
DISPLAY INVISIBLE (1525 3650);
FORCEADD TAP..7
(2125 3100);
FORCEPROP 3 LASTPIN (2125 3150) SIG_NAME P3E_CPU0_PE2_SS_C_TXN<1>
J 0
(2135 3160);
DISPLAY 0.659574 (2135 3160);
PAINT MONO (2135 3160);
DISPLAY INVISIBLE (2135 3160);
FORCEPROP 1 LASTPIN (2125 3150) BN 1
R 1
J 0
(2118 3098);
DISPLAY 0.617021 (2118 3098);
PAINT GREEN (2118 3098);
FORCEPROP 2 LAST CDS_LIB mstr_standard
J 0
(2125 3100);
PAINT ORANGE (2125 3100);
DISPLAY INVISIBLE (2125 3100);
FORCEPROP 1 LAST BODY_TYPE PLUMBING
J 0
(2175 3100);
DISPLAY 2.276596 (2175 3100);
PAINT GREEN (2175 3100);
DISPLAY INVISIBLE (2175 3100);
FORCEPROP 1 LAST HDL_TAP TRUE
J 0
(2445 2970);
DISPLAY 2.276596 (2445 2970);
PAINT GREEN (2445 2970);
DISPLAY INVISIBLE (2445 2970);
FORCEPROP 1 LAST PATH I59
J 0
(2123 3100);
DISPLAY 0.872340 (2123 3100);
PAINT GREEN (2123 3100);
DISPLAY INVISIBLE (2123 3100);
FORCEADD CAP..1
R 2
(-700 3350);
FORCEPROP 1 LAST LOCATION C7G6
J 2
(-750 3450);
DISPLAY 0.617021 (-750 3450);
PAINT AQUA (-750 3450);
FORCEPROP 1 LAST PART_NUMBER A36096-155
J 2
(-750 3200);
DISPLAY 0.617021 (-750 3200);
PAINT BLUE (-750 3200);
FORCEPROP 1 LAST VALUE 0.22UF
J 2
(-750 3400);
DISPLAY 0.617021 (-750 3400);
PAINT SKYBLUE (-750 3400);
FORCEPROP 1 LAST TOLERANCE 10%
J 2
(-750 3300);
DISPLAY 0.617021 (-750 3300);
PAINT SKYBLUE (-750 3300);
FORCEPROP 1 LAST PACK_TYPE 0402
J 2
(-750 3150);
DISPLAY 0.617021 (-750 3150);
PAINT SKYBLUE (-750 3150);
FORCEPROP 1 LAST VOLTAGE 16V
J 2
(-750 3350);
DISPLAY 0.617021 (-750 3350);
PAINT SKYBLUE (-750 3350);
FORCEPROP 1 LAST MATERIAL X7R
J 2
(-750 3250);
DISPLAY 0.617021 (-750 3250);
PAINT SKYBLUE (-750 3250);
FORCEPROP 2 LAST CDS_LIB mstr_discrete
J 0
(-700 3350);
PAINT ORANGE (-700 3350);
DISPLAY INVISIBLE (-700 3350);
FORCEPROP 2 LAST CDS_SEC 1
J 0
(-750 3550);
DISPLAY 1.021277 (-750 3550);
PAINT ORANGE (-750 3550);
DISPLAY INVISIBLE (-750 3550);
FORCEPROP 2 LAST $SEC 1
J 0
(-750 3550);
DISPLAY 0.680851 (-750 3550);
PAINT MONO (-750 3550);
DISPLAY INVISIBLE (-750 3550);
FORCEPROP 2 LAST CDS_LOCATION C7G6
J 2
(-750 3450);
DISPLAY 0.617021 (-750 3450);
PAINT AQUA (-750 3450);
DISPLAY INVISIBLE (-750 3450);
FORCEPROP 1 LAST PATH I6
J 2
(-750 3500);
DISPLAY 0.978723 (-750 3500);
PAINT WHITE (-750 3500);
DISPLAY INVISIBLE (-750 3500);
FORCEPROP 2 LAST ROOM OCP_STEERING
J 2
(-700 3350);
PAINT MONO (-700 3350);
DISPLAY INVISIBLE (-700 3350);
FORCEPROP 1 LASTPIN (-700 3250) $PN 2
J 2
(-710 3230);
DISPLAY 0.787234 (-710 3230);
PAINT ORANGE (-710 3230);
DISPLAY INVISIBLE (-710 3230);
FORCEPROP 1 LASTPIN (-700 3450) $PN 1
J 2
(-710 3430);
DISPLAY 0.787234 (-710 3430);
PAINT ORANGE (-710 3430);
DISPLAY INVISIBLE (-710 3430);
FORCEADD TAP..7
(1925 3100);
FORCEPROP 3 LASTPIN (1925 3150) SIG_NAME P3E_CPU0_PE2_SS_C_TXN<2>
J 0
(1935 3160);
DISPLAY 0.659574 (1935 3160);
PAINT MONO (1935 3160);
DISPLAY INVISIBLE (1935 3160);
FORCEPROP 1 LASTPIN (1925 3150) BN 2
R 1
J 0
(1918 3098);
DISPLAY 0.617021 (1918 3098);
PAINT GREEN (1918 3098);
FORCEPROP 2 LAST CDS_LIB mstr_standard
J 0
(1925 3100);
PAINT ORANGE (1925 3100);
DISPLAY INVISIBLE (1925 3100);
FORCEPROP 1 LAST BODY_TYPE PLUMBING
J 0
(1975 3100);
DISPLAY 2.276596 (1975 3100);
PAINT GREEN (1975 3100);
DISPLAY INVISIBLE (1975 3100);
FORCEPROP 1 LAST HDL_TAP TRUE
J 0
(2245 2970);
DISPLAY 2.276596 (2245 2970);
PAINT GREEN (2245 2970);
DISPLAY INVISIBLE (2245 2970);
FORCEPROP 1 LAST PATH I60
J 0
(1923 3100);
DISPLAY 0.872340 (1923 3100);
PAINT GREEN (1923 3100);
DISPLAY INVISIBLE (1923 3100);
FORCEADD CAP..1
R 2
(1925 3650);
FORCEPROP 1 LAST LOCATION C8G6
J 2
(1875 3750);
DISPLAY 0.617021 (1875 3750);
PAINT AQUA (1875 3750);
FORCEPROP 1 LAST PART_NUMBER A36096-155
J 2
(1875 3500);
DISPLAY 0.617021 (1875 3500);
PAINT BLUE (1875 3500);
FORCEPROP 1 LAST VALUE 0.22UF
J 2
(1875 3700);
DISPLAY 0.617021 (1875 3700);
PAINT SKYBLUE (1875 3700);
FORCEPROP 1 LAST TOLERANCE 10%
J 2
(1875 3600);
DISPLAY 0.617021 (1875 3600);
PAINT SKYBLUE (1875 3600);
FORCEPROP 1 LAST PACK_TYPE 0402
J 2
(1875 3450);
DISPLAY 0.617021 (1875 3450);
PAINT SKYBLUE (1875 3450);
FORCEPROP 1 LAST VOLTAGE 16V
J 2
(1875 3650);
DISPLAY 0.617021 (1875 3650);
PAINT SKYBLUE (1875 3650);
FORCEPROP 1 LAST MATERIAL X7R
J 2
(1875 3550);
DISPLAY 0.617021 (1875 3550);
PAINT SKYBLUE (1875 3550);
FORCEPROP 1 LASTPIN (1925 3550) $PN 2
J 2
(1915 3530);
DISPLAY 0.617021 (1915 3530);
PAINT ORANGE (1915 3530);
FORCEPROP 1 LASTPIN (1925 3750) $PN 1
J 2
(1915 3730);
DISPLAY 0.617021 (1915 3730);
PAINT ORANGE (1915 3730);
FORCEPROP 2 LAST CDS_LIB mstr_discrete
J 0
(1925 3650);
PAINT ORANGE (1925 3650);
DISPLAY INVISIBLE (1925 3650);
FORCEPROP 2 LAST SEC_TYPE 0402
J 0
(1875 3850);
DISPLAY 1.021277 (1875 3850);
PAINT ORANGE (1875 3850);
DISPLAY INVISIBLE (1875 3850);
FORCEPROP 2 LAST SEC 1
J 0
(1875 3850);
DISPLAY 0.680851 (1875 3850);
PAINT MONO (1875 3850);
DISPLAY INVISIBLE (1875 3850);
FORCEPROP 2 LAST CDS_LOCATION C8G6
J 2
(1875 3750);
DISPLAY 0.617021 (1875 3750);
PAINT AQUA (1875 3750);
DISPLAY INVISIBLE (1875 3750);
FORCEPROP 1 LAST PATH I61
J 2
(1875 3800);
DISPLAY 0.978723 (1875 3800);
PAINT WHITE (1875 3800);
DISPLAY INVISIBLE (1875 3800);
FORCEPROP 2 LAST ROOM OCP_STEERING
J 2
(1925 3650);
PAINT MONO (1925 3650);
DISPLAY INVISIBLE (1925 3650);
FORCEADD CAP..1
R 2
(2125 3350);
FORCEPROP 1 LAST LOCATION C8G7
J 2
(2075 3450);
DISPLAY 0.617021 (2075 3450);
PAINT AQUA (2075 3450);
FORCEPROP 1 LAST PART_NUMBER A36096-155
J 2
(2075 3200);
DISPLAY 0.617021 (2075 3200);
PAINT BLUE (2075 3200);
FORCEPROP 1 LAST VALUE 0.22UF
J 2
(2075 3400);
DISPLAY 0.617021 (2075 3400);
PAINT SKYBLUE (2075 3400);
FORCEPROP 1 LAST TOLERANCE 10%
J 2
(2075 3300);
DISPLAY 0.617021 (2075 3300);
PAINT SKYBLUE (2075 3300);
FORCEPROP 1 LAST PACK_TYPE 0402
J 2
(2075 3150);
DISPLAY 0.617021 (2075 3150);
PAINT SKYBLUE (2075 3150);
FORCEPROP 1 LAST VOLTAGE 16V
J 2
(2075 3350);
DISPLAY 0.617021 (2075 3350);
PAINT SKYBLUE (2075 3350);
FORCEPROP 1 LAST MATERIAL X7R
J 2
(2075 3250);
DISPLAY 0.617021 (2075 3250);
PAINT SKYBLUE (2075 3250);
FORCEPROP 1 LASTPIN (2125 3250) $PN 2
J 2
(2115 3230);
DISPLAY 0.617021 (2115 3230);
PAINT ORANGE (2115 3230);
FORCEPROP 1 LASTPIN (2125 3450) $PN 1
J 2
(2115 3430);
DISPLAY 0.617021 (2115 3430);
PAINT ORANGE (2115 3430);
FORCEPROP 2 LAST CDS_LIB mstr_discrete
J 0
(2125 3350);
PAINT ORANGE (2125 3350);
DISPLAY INVISIBLE (2125 3350);
FORCEPROP 2 LAST SEC_TYPE 0402
J 0
(2075 3550);
DISPLAY 1.021277 (2075 3550);
PAINT ORANGE (2075 3550);
DISPLAY INVISIBLE (2075 3550);
FORCEPROP 2 LAST SEC 1
J 0
(2075 3550);
DISPLAY 0.680851 (2075 3550);
PAINT MONO (2075 3550);
DISPLAY INVISIBLE (2075 3550);
FORCEPROP 2 LAST CDS_LOCATION C8G7
J 2
(2075 3450);
DISPLAY 0.617021 (2075 3450);
PAINT AQUA (2075 3450);
DISPLAY INVISIBLE (2075 3450);
FORCEPROP 1 LAST PATH I62
J 2
(2075 3500);
DISPLAY 0.978723 (2075 3500);
PAINT WHITE (2075 3500);
DISPLAY INVISIBLE (2075 3500);
FORCEPROP 2 LAST ROOM OCP_STEERING
J 2
(2125 3350);
PAINT MONO (2125 3350);
DISPLAY INVISIBLE (2125 3350);
FORCEADD TAP..3
(1325 3900);
FORCEPROP 3 LASTPIN (1325 3850) SIG_NAME P3E_CPU0_PE2_SS_TXN<5>
J 0
(1335 3860);
DISPLAY 0.659574 (1335 3860);
PAINT MONO (1335 3860);
DISPLAY INVISIBLE (1335 3860);
FORCEPROP 1 LASTPIN (1325 3850) BN 5
R 1
J 0
(1318 3838);
DISPLAY 0.617021 (1318 3838);
PAINT GREEN (1318 3838);
FORCEPROP 2 LAST CDS_LIB mstr_standard
J 0
(1325 3900);
PAINT ORANGE (1325 3900);
DISPLAY INVISIBLE (1325 3900);
FORCEPROP 1 LAST BODY_TYPE PLUMBING
J 0
(1375 3850);
DISPLAY 2.276596 (1375 3850);
PAINT GREEN (1375 3850);
DISPLAY INVISIBLE (1375 3850);
FORCEPROP 1 LAST HDL_TAP TRUE
J 0
(1645 3770);
DISPLAY 2.276596 (1645 3770);
PAINT GREEN (1645 3770);
DISPLAY INVISIBLE (1645 3770);
FORCEPROP 1 LAST PATH I63
J 0
(1323 3900);
DISPLAY 0.872340 (1323 3900);
PAINT GREEN (1323 3900);
DISPLAY INVISIBLE (1323 3900);
FORCEADD TAP..7
(1275 4100);
FORCEPROP 3 LASTPIN (1275 4150) SIG_NAME P3E_CPU0_PE2_SS_C_TXP<5>
J 0
(1285 4160);
DISPLAY 0.659574 (1285 4160);
PAINT MONO (1285 4160);
DISPLAY INVISIBLE (1285 4160);
FORCEPROP 1 LASTPIN (1275 4150) BN 5
R 1
J 0
(1268 4098);
DISPLAY 0.617021 (1268 4098);
PAINT GREEN (1268 4098);
FORCEPROP 2 LAST CDS_LIB mstr_standard
J 0
(1275 4100);
PAINT ORANGE (1275 4100);
DISPLAY INVISIBLE (1275 4100);
FORCEPROP 1 LAST BODY_TYPE PLUMBING
J 0
(1325 4100);
DISPLAY 2.276596 (1325 4100);
PAINT GREEN (1325 4100);
DISPLAY INVISIBLE (1325 4100);
FORCEPROP 1 LAST HDL_TAP TRUE
J 0
(1595 3970);
DISPLAY 2.276596 (1595 3970);
PAINT GREEN (1595 3970);
DISPLAY INVISIBLE (1595 3970);
FORCEPROP 1 LAST PATH I64
J 0
(1273 4100);
DISPLAY 0.872340 (1273 4100);
PAINT GREEN (1273 4100);
DISPLAY INVISIBLE (1273 4100);
FORCEADD TAP..3
(1525 3900);
FORCEPROP 3 LASTPIN (1525 3850) SIG_NAME P3E_CPU0_PE2_SS_TXN<4>
J 0
(1535 3860);
DISPLAY 0.659574 (1535 3860);
PAINT MONO (1535 3860);
DISPLAY INVISIBLE (1535 3860);
FORCEPROP 1 LASTPIN (1525 3850) BN 4
R 1
J 0
(1518 3838);
DISPLAY 0.617021 (1518 3838);
PAINT GREEN (1518 3838);
FORCEPROP 2 LAST CDS_LIB mstr_standard
J 0
(1525 3900);
PAINT ORANGE (1525 3900);
DISPLAY INVISIBLE (1525 3900);
FORCEPROP 1 LAST BODY_TYPE PLUMBING
J 0
(1575 3850);
DISPLAY 2.276596 (1575 3850);
PAINT GREEN (1575 3850);
DISPLAY INVISIBLE (1575 3850);
FORCEPROP 1 LAST HDL_TAP TRUE
J 0
(1845 3770);
DISPLAY 2.276596 (1845 3770);
PAINT GREEN (1845 3770);
DISPLAY INVISIBLE (1845 3770);
FORCEPROP 1 LAST PATH I65
J 0
(1523 3900);
DISPLAY 0.872340 (1523 3900);
PAINT GREEN (1523 3900);
DISPLAY INVISIBLE (1523 3900);
FORCEADD TAP..7
(1475 4100);
FORCEPROP 3 LASTPIN (1475 4150) SIG_NAME P3E_CPU0_PE2_SS_C_TXP<4>
J 0
(1485 4160);
DISPLAY 0.659574 (1485 4160);
PAINT MONO (1485 4160);
DISPLAY INVISIBLE (1485 4160);
FORCEPROP 1 LASTPIN (1475 4150) BN 4
R 1
J 0
(1468 4098);
DISPLAY 0.617021 (1468 4098);
PAINT GREEN (1468 4098);
FORCEPROP 2 LAST CDS_LIB mstr_standard
J 0
(1475 4100);
PAINT ORANGE (1475 4100);
DISPLAY INVISIBLE (1475 4100);
FORCEPROP 1 LAST BODY_TYPE PLUMBING
J 0
(1525 4100);
DISPLAY 2.276596 (1525 4100);
PAINT GREEN (1525 4100);
DISPLAY INVISIBLE (1525 4100);
FORCEPROP 1 LAST HDL_TAP TRUE
J 0
(1795 3970);
DISPLAY 2.276596 (1795 3970);
PAINT GREEN (1795 3970);
DISPLAY INVISIBLE (1795 3970);
FORCEPROP 1 LAST PATH I66
J 0
(1473 4100);
DISPLAY 0.872340 (1473 4100);
PAINT GREEN (1473 4100);
DISPLAY INVISIBLE (1473 4100);
FORCEADD TAP..7
(1675 4100);
FORCEPROP 3 LASTPIN (1675 4150) SIG_NAME P3E_CPU0_PE2_SS_C_TXP<3>
J 0
(1685 4160);
DISPLAY 0.659574 (1685 4160);
PAINT MONO (1685 4160);
DISPLAY INVISIBLE (1685 4160);
FORCEPROP 1 LASTPIN (1675 4150) BN 3
R 1
J 0
(1668 4098);
DISPLAY 0.617021 (1668 4098);
PAINT GREEN (1668 4098);
FORCEPROP 2 LAST CDS_LIB mstr_standard
J 0
(1675 4100);
PAINT ORANGE (1675 4100);
DISPLAY INVISIBLE (1675 4100);
FORCEPROP 1 LAST BODY_TYPE PLUMBING
J 0
(1725 4100);
DISPLAY 2.276596 (1725 4100);
PAINT GREEN (1725 4100);
DISPLAY INVISIBLE (1725 4100);
FORCEPROP 1 LAST HDL_TAP TRUE
J 0
(1995 3970);
DISPLAY 2.276596 (1995 3970);
PAINT GREEN (1995 3970);
DISPLAY INVISIBLE (1995 3970);
FORCEPROP 1 LAST PATH I67
J 0
(1673 4100);
DISPLAY 0.872340 (1673 4100);
PAINT GREEN (1673 4100);
DISPLAY INVISIBLE (1673 4100);
FORCEADD TAP..3
(1725 3900);
FORCEPROP 3 LASTPIN (1725 3850) SIG_NAME P3E_CPU0_PE2_SS_TXN<3>
J 0
(1735 3860);
DISPLAY 0.659574 (1735 3860);
PAINT MONO (1735 3860);
DISPLAY INVISIBLE (1735 3860);
FORCEPROP 1 LASTPIN (1725 3850) BN 3
R 1
J 0
(1718 3838);
DISPLAY 0.617021 (1718 3838);
PAINT GREEN (1718 3838);
FORCEPROP 2 LAST CDS_LIB mstr_standard
J 0
(1725 3900);
PAINT ORANGE (1725 3900);
DISPLAY INVISIBLE (1725 3900);
FORCEPROP 1 LAST BODY_TYPE PLUMBING
J 0
(1775 3850);
DISPLAY 2.276596 (1775 3850);
PAINT GREEN (1775 3850);
DISPLAY INVISIBLE (1775 3850);
FORCEPROP 1 LAST HDL_TAP TRUE
J 0
(2045 3770);
DISPLAY 2.276596 (2045 3770);
PAINT GREEN (2045 3770);
DISPLAY INVISIBLE (2045 3770);
FORCEPROP 1 LAST PATH I68
J 0
(1723 3900);
DISPLAY 0.872340 (1723 3900);
PAINT GREEN (1723 3900);
DISPLAY INVISIBLE (1723 3900);
FORCEADD CAP..1
R 2
(1275 4350);
FORCEPROP 1 LAST LOCATION C7G25
J 2
(1225 4450);
DISPLAY 0.617021 (1225 4450);
PAINT AQUA (1225 4450);
FORCEPROP 1 LAST PART_NUMBER A36096-155
J 2
(1225 4200);
DISPLAY 0.617021 (1225 4200);
PAINT BLUE (1225 4200);
FORCEPROP 1 LAST VALUE 0.22UF
J 2
(1225 4400);
DISPLAY 0.617021 (1225 4400);
PAINT SKYBLUE (1225 4400);
FORCEPROP 1 LAST TOLERANCE 10%
J 2
(1225 4300);
DISPLAY 0.617021 (1225 4300);
PAINT SKYBLUE (1225 4300);
FORCEPROP 1 LAST PACK_TYPE 0402
J 2
(1225 4150);
DISPLAY 0.617021 (1225 4150);
PAINT SKYBLUE (1225 4150);
FORCEPROP 1 LAST VOLTAGE 16V
J 2
(1225 4350);
DISPLAY 0.617021 (1225 4350);
PAINT SKYBLUE (1225 4350);
FORCEPROP 1 LAST MATERIAL X7R
J 2
(1225 4250);
DISPLAY 0.617021 (1225 4250);
PAINT SKYBLUE (1225 4250);
FORCEPROP 1 LASTPIN (1275 4250) $PN 2
J 2
(1265 4230);
DISPLAY 0.617021 (1265 4230);
PAINT ORANGE (1265 4230);
FORCEPROP 1 LASTPIN (1275 4450) $PN 1
J 2
(1265 4430);
DISPLAY 0.617021 (1265 4430);
PAINT ORANGE (1265 4430);
FORCEPROP 2 LAST CDS_LIB mstr_discrete
J 0
(1275 4350);
PAINT ORANGE (1275 4350);
DISPLAY INVISIBLE (1275 4350);
FORCEPROP 2 LAST SEC_TYPE 0402
J 0
(1225 4550);
DISPLAY 1.021277 (1225 4550);
PAINT ORANGE (1225 4550);
DISPLAY INVISIBLE (1225 4550);
FORCEPROP 2 LAST SEC 1
J 0
(1225 4550);
DISPLAY 0.680851 (1225 4550);
PAINT MONO (1225 4550);
DISPLAY INVISIBLE (1225 4550);
FORCEPROP 2 LAST CDS_LOCATION C7G25
J 2
(1225 4450);
DISPLAY 0.617021 (1225 4450);
PAINT AQUA (1225 4450);
DISPLAY INVISIBLE (1225 4450);
FORCEPROP 1 LAST PATH I69
J 2
(1225 4500);
DISPLAY 0.978723 (1225 4500);
PAINT WHITE (1225 4500);
DISPLAY INVISIBLE (1225 4500);
FORCEPROP 2 LAST ROOM OCP_STEERING
J 2
(1275 4350);
PAINT MONO (1275 4350);
DISPLAY INVISIBLE (1275 4350);
FORCEADD CAP..1
R 2
(-500 3650);
FORCEPROP 1 LAST LOCATION C7G7
J 2
(-550 3750);
DISPLAY 0.617021 (-550 3750);
PAINT AQUA (-550 3750);
FORCEPROP 1 LAST PART_NUMBER A36096-155
J 2
(-550 3500);
DISPLAY 0.617021 (-550 3500);
PAINT BLUE (-550 3500);
FORCEPROP 1 LAST VALUE 0.22UF
J 2
(-550 3700);
DISPLAY 0.617021 (-550 3700);
PAINT SKYBLUE (-550 3700);
FORCEPROP 1 LAST TOLERANCE 10%
J 2
(-550 3600);
DISPLAY 0.617021 (-550 3600);
PAINT SKYBLUE (-550 3600);
FORCEPROP 1 LAST PACK_TYPE 0402
J 2
(-550 3450);
DISPLAY 0.617021 (-550 3450);
PAINT SKYBLUE (-550 3450);
FORCEPROP 1 LAST VOLTAGE 16V
J 2
(-550 3650);
DISPLAY 0.617021 (-550 3650);
PAINT SKYBLUE (-550 3650);
FORCEPROP 1 LAST MATERIAL X7R
J 2
(-550 3550);
DISPLAY 0.617021 (-550 3550);
PAINT SKYBLUE (-550 3550);
FORCEPROP 1 LASTPIN (-500 3550) $PN 2
J 2
(-510 3530);
DISPLAY 0.617021 (-510 3530);
PAINT ORANGE (-510 3530);
FORCEPROP 1 LASTPIN (-500 3750) $PN 1
J 2
(-510 3730);
DISPLAY 0.617021 (-510 3730);
PAINT ORANGE (-510 3730);
FORCEPROP 2 LAST SEC_TYPE 0402
J 0
(-550 3850);
DISPLAY 1.021277 (-550 3850);
PAINT ORANGE (-550 3850);
DISPLAY INVISIBLE (-550 3850);
FORCEPROP 2 LAST CDS_LIB mstr_discrete
J 0
(-500 3650);
PAINT ORANGE (-500 3650);
DISPLAY INVISIBLE (-500 3650);
FORCEPROP 2 LAST SEC 1
J 0
(-550 3850);
DISPLAY 0.680851 (-550 3850);
PAINT MONO (-550 3850);
DISPLAY INVISIBLE (-550 3850);
FORCEPROP 2 LAST CDS_LOCATION C7G7
J 2
(-550 3750);
DISPLAY 0.617021 (-550 3750);
PAINT AQUA (-550 3750);
DISPLAY INVISIBLE (-550 3750);
FORCEPROP 1 LAST PATH I7
J 2
(-550 3800);
DISPLAY 0.978723 (-550 3800);
PAINT WHITE (-550 3800);
DISPLAY INVISIBLE (-550 3800);
FORCEPROP 2 LAST ROOM OCP_STEERING
J 2
(-500 3650);
PAINT MONO (-500 3650);
DISPLAY INVISIBLE (-500 3650);
FORCEADD CAP..1
R 2
(1475 4650);
FORCEPROP 1 LAST LOCATION C8G1
J 2
(1425 4750);
DISPLAY 0.617021 (1425 4750);
PAINT AQUA (1425 4750);
FORCEPROP 1 LAST PART_NUMBER A36096-155
J 2
(1425 4500);
DISPLAY 0.617021 (1425 4500);
PAINT BLUE (1425 4500);
FORCEPROP 1 LAST VALUE 0.22UF
J 2
(1425 4700);
DISPLAY 0.617021 (1425 4700);
PAINT SKYBLUE (1425 4700);
FORCEPROP 1 LAST TOLERANCE 10%
J 2
(1425 4600);
DISPLAY 0.617021 (1425 4600);
PAINT SKYBLUE (1425 4600);
FORCEPROP 1 LAST PACK_TYPE 0402
J 2
(1425 4450);
DISPLAY 0.617021 (1425 4450);
PAINT SKYBLUE (1425 4450);
FORCEPROP 1 LAST VOLTAGE 16V
J 2
(1425 4650);
DISPLAY 0.617021 (1425 4650);
PAINT SKYBLUE (1425 4650);
FORCEPROP 1 LAST MATERIAL X7R
J 2
(1425 4550);
DISPLAY 0.617021 (1425 4550);
PAINT SKYBLUE (1425 4550);
FORCEPROP 1 LASTPIN (1475 4550) $PN 2
J 2
(1465 4530);
DISPLAY 0.617021 (1465 4530);
PAINT ORANGE (1465 4530);
FORCEPROP 1 LASTPIN (1475 4750) $PN 1
J 2
(1465 4730);
DISPLAY 0.617021 (1465 4730);
PAINT ORANGE (1465 4730);
FORCEPROP 2 LAST CDS_LIB mstr_discrete
J 0
(1475 4650);
PAINT ORANGE (1475 4650);
DISPLAY INVISIBLE (1475 4650);
FORCEPROP 2 LAST SEC_TYPE 0402
J 0
(1425 4850);
DISPLAY 1.021277 (1425 4850);
PAINT ORANGE (1425 4850);
DISPLAY INVISIBLE (1425 4850);
FORCEPROP 2 LAST SEC 1
J 0
(1425 4850);
DISPLAY 0.680851 (1425 4850);
PAINT MONO (1425 4850);
DISPLAY INVISIBLE (1425 4850);
FORCEPROP 2 LAST CDS_LOCATION C8G1
J 2
(1425 4750);
DISPLAY 0.617021 (1425 4750);
PAINT AQUA (1425 4750);
DISPLAY INVISIBLE (1425 4750);
FORCEPROP 1 LAST PATH I70
J 2
(1425 4800);
DISPLAY 0.978723 (1425 4800);
PAINT WHITE (1425 4800);
DISPLAY INVISIBLE (1425 4800);
FORCEPROP 2 LAST ROOM OCP_STEERING
J 2
(1475 4650);
PAINT MONO (1475 4650);
DISPLAY INVISIBLE (1475 4650);
FORCEADD CAP..1
R 2
(1675 4350);
FORCEPROP 1 LAST LOCATION C8G3
J 2
(1625 4450);
DISPLAY 0.617021 (1625 4450);
PAINT AQUA (1625 4450);
FORCEPROP 1 LAST PART_NUMBER A36096-155
J 2
(1625 4200);
DISPLAY 0.617021 (1625 4200);
PAINT BLUE (1625 4200);
FORCEPROP 1 LAST VALUE 0.22UF
J 2
(1625 4400);
DISPLAY 0.617021 (1625 4400);
PAINT SKYBLUE (1625 4400);
FORCEPROP 1 LAST TOLERANCE 10%
J 2
(1625 4300);
DISPLAY 0.617021 (1625 4300);
PAINT SKYBLUE (1625 4300);
FORCEPROP 1 LAST PACK_TYPE 0402
J 2
(1625 4150);
DISPLAY 0.617021 (1625 4150);
PAINT SKYBLUE (1625 4150);
FORCEPROP 1 LAST VOLTAGE 16V
J 2
(1625 4350);
DISPLAY 0.617021 (1625 4350);
PAINT SKYBLUE (1625 4350);
FORCEPROP 1 LAST MATERIAL X7R
J 2
(1625 4250);
DISPLAY 0.617021 (1625 4250);
PAINT SKYBLUE (1625 4250);
FORCEPROP 1 LASTPIN (1675 4250) $PN 2
J 2
(1665 4230);
DISPLAY 0.617021 (1665 4230);
PAINT ORANGE (1665 4230);
FORCEPROP 1 LASTPIN (1675 4450) $PN 1
J 2
(1665 4430);
DISPLAY 0.617021 (1665 4430);
PAINT ORANGE (1665 4430);
FORCEPROP 2 LAST CDS_LIB mstr_discrete
J 0
(1675 4350);
PAINT ORANGE (1675 4350);
DISPLAY INVISIBLE (1675 4350);
FORCEPROP 2 LAST SEC_TYPE 0402
J 0
(1625 4550);
DISPLAY 1.021277 (1625 4550);
PAINT ORANGE (1625 4550);
DISPLAY INVISIBLE (1625 4550);
FORCEPROP 2 LAST SEC 1
J 0
(1625 4550);
DISPLAY 0.680851 (1625 4550);
PAINT MONO (1625 4550);
DISPLAY INVISIBLE (1625 4550);
FORCEPROP 2 LAST CDS_LOCATION C8G3
J 2
(1625 4450);
DISPLAY 0.617021 (1625 4450);
PAINT AQUA (1625 4450);
DISPLAY INVISIBLE (1625 4450);
FORCEPROP 1 LAST PATH I71
J 2
(1625 4500);
DISPLAY 0.978723 (1625 4500);
PAINT WHITE (1625 4500);
DISPLAY INVISIBLE (1625 4500);
FORCEPROP 2 LAST ROOM OCP_STEERING
J 2
(1675 4350);
PAINT MONO (1675 4350);
DISPLAY INVISIBLE (1675 4350);
FORCEADD TAP..7
(1875 4100);
FORCEPROP 3 LASTPIN (1875 4150) SIG_NAME P3E_CPU0_PE2_SS_C_TXP<2>
J 0
(1885 4160);
DISPLAY 0.659574 (1885 4160);
PAINT MONO (1885 4160);
DISPLAY INVISIBLE (1885 4160);
FORCEPROP 1 LASTPIN (1875 4150) BN 2
R 1
J 0
(1868 4098);
DISPLAY 0.617021 (1868 4098);
PAINT GREEN (1868 4098);
FORCEPROP 2 LAST CDS_LIB mstr_standard
J 0
(1875 4100);
PAINT ORANGE (1875 4100);
DISPLAY INVISIBLE (1875 4100);
FORCEPROP 1 LAST BODY_TYPE PLUMBING
J 0
(1925 4100);
DISPLAY 2.276596 (1925 4100);
PAINT GREEN (1925 4100);
DISPLAY INVISIBLE (1925 4100);
FORCEPROP 1 LAST HDL_TAP TRUE
J 0
(2195 3970);
DISPLAY 2.276596 (2195 3970);
PAINT GREEN (2195 3970);
DISPLAY INVISIBLE (2195 3970);
FORCEPROP 1 LAST PATH I72
J 0
(1873 4100);
DISPLAY 0.872340 (1873 4100);
PAINT GREEN (1873 4100);
DISPLAY INVISIBLE (1873 4100);
FORCEADD TAP..3
(2125 3900);
FORCEPROP 3 LASTPIN (2125 3850) SIG_NAME P3E_CPU0_PE2_SS_TXN<1>
J 0
(2135 3860);
DISPLAY 0.659574 (2135 3860);
PAINT MONO (2135 3860);
DISPLAY INVISIBLE (2135 3860);
FORCEPROP 1 LASTPIN (2125 3850) BN 1
R 1
J 0
(2118 3838);
DISPLAY 0.617021 (2118 3838);
PAINT GREEN (2118 3838);
FORCEPROP 2 LAST CDS_LIB mstr_standard
J 0
(2125 3900);
PAINT ORANGE (2125 3900);
DISPLAY INVISIBLE (2125 3900);
FORCEPROP 1 LAST BODY_TYPE PLUMBING
J 0
(2175 3850);
DISPLAY 2.276596 (2175 3850);
PAINT GREEN (2175 3850);
DISPLAY INVISIBLE (2175 3850);
FORCEPROP 1 LAST HDL_TAP TRUE
J 0
(2445 3770);
DISPLAY 2.276596 (2445 3770);
PAINT GREEN (2445 3770);
DISPLAY INVISIBLE (2445 3770);
FORCEPROP 1 LAST PATH I73
J 0
(2123 3900);
DISPLAY 0.872340 (2123 3900);
PAINT GREEN (2123 3900);
DISPLAY INVISIBLE (2123 3900);
FORCEADD TAP..7
(2075 4100);
FORCEPROP 3 LASTPIN (2075 4150) SIG_NAME P3E_CPU0_PE2_SS_C_TXP<1>
J 0
(2085 4160);
DISPLAY 0.659574 (2085 4160);
PAINT MONO (2085 4160);
DISPLAY INVISIBLE (2085 4160);
FORCEPROP 1 LASTPIN (2075 4150) BN 1
R 1
J 0
(2068 4098);
DISPLAY 0.617021 (2068 4098);
PAINT GREEN (2068 4098);
FORCEPROP 2 LAST CDS_LIB mstr_standard
J 0
(2075 4100);
PAINT ORANGE (2075 4100);
DISPLAY INVISIBLE (2075 4100);
FORCEPROP 1 LAST BODY_TYPE PLUMBING
J 0
(2125 4100);
DISPLAY 2.276596 (2125 4100);
PAINT GREEN (2125 4100);
DISPLAY INVISIBLE (2125 4100);
FORCEPROP 1 LAST HDL_TAP TRUE
J 0
(2395 3970);
DISPLAY 2.276596 (2395 3970);
PAINT GREEN (2395 3970);
DISPLAY INVISIBLE (2395 3970);
FORCEPROP 1 LAST PATH I74
J 0
(2073 4100);
DISPLAY 0.872340 (2073 4100);
PAINT GREEN (2073 4100);
DISPLAY INVISIBLE (2073 4100);
FORCEADD CAP..1
R 2
(1875 4650);
FORCEPROP 1 LAST LOCATION C8G5
J 2
(1825 4750);
DISPLAY 0.617021 (1825 4750);
PAINT AQUA (1825 4750);
FORCEPROP 1 LAST PART_NUMBER A36096-155
J 2
(1825 4500);
DISPLAY 0.617021 (1825 4500);
PAINT BLUE (1825 4500);
FORCEPROP 1 LAST VALUE 0.22UF
J 2
(1825 4700);
DISPLAY 0.617021 (1825 4700);
PAINT SKYBLUE (1825 4700);
FORCEPROP 1 LAST TOLERANCE 10%
J 2
(1825 4600);
DISPLAY 0.617021 (1825 4600);
PAINT SKYBLUE (1825 4600);
FORCEPROP 1 LAST PACK_TYPE 0402
J 2
(1825 4450);
DISPLAY 0.617021 (1825 4450);
PAINT SKYBLUE (1825 4450);
FORCEPROP 1 LAST VOLTAGE 16V
J 2
(1825 4650);
DISPLAY 0.617021 (1825 4650);
PAINT SKYBLUE (1825 4650);
FORCEPROP 1 LAST MATERIAL X7R
J 2
(1825 4550);
DISPLAY 0.617021 (1825 4550);
PAINT SKYBLUE (1825 4550);
FORCEPROP 1 LASTPIN (1875 4550) $PN 2
J 2
(1865 4530);
DISPLAY 0.617021 (1865 4530);
PAINT ORANGE (1865 4530);
FORCEPROP 1 LASTPIN (1875 4750) $PN 1
J 2
(1865 4730);
DISPLAY 0.617021 (1865 4730);
PAINT ORANGE (1865 4730);
FORCEPROP 2 LAST CDS_LIB mstr_discrete
J 0
(1875 4650);
PAINT ORANGE (1875 4650);
DISPLAY INVISIBLE (1875 4650);
FORCEPROP 2 LAST SEC_TYPE 0402
J 0
(1825 4850);
DISPLAY 1.021277 (1825 4850);
PAINT ORANGE (1825 4850);
DISPLAY INVISIBLE (1825 4850);
FORCEPROP 2 LAST SEC 1
J 0
(1825 4850);
DISPLAY 0.680851 (1825 4850);
PAINT MONO (1825 4850);
DISPLAY INVISIBLE (1825 4850);
FORCEPROP 2 LAST CDS_LOCATION C8G5
J 2
(1825 4750);
DISPLAY 0.617021 (1825 4750);
PAINT AQUA (1825 4750);
DISPLAY INVISIBLE (1825 4750);
FORCEPROP 1 LAST PATH I75
J 2
(1825 4800);
DISPLAY 0.978723 (1825 4800);
PAINT WHITE (1825 4800);
DISPLAY INVISIBLE (1825 4800);
FORCEPROP 2 LAST ROOM OCP_STEERING
J 2
(1875 4650);
PAINT MONO (1875 4650);
DISPLAY INVISIBLE (1875 4650);
FORCEADD CAP..1
R 2
(2075 4350);
FORCEPROP 1 LAST LOCATION C8G8
J 2
(2025 4450);
DISPLAY 0.617021 (2025 4450);
PAINT AQUA (2025 4450);
FORCEPROP 1 LAST PART_NUMBER A36096-155
J 2
(2025 4200);
DISPLAY 0.617021 (2025 4200);
PAINT BLUE (2025 4200);
FORCEPROP 1 LAST VALUE 0.22UF
J 2
(2025 4400);
DISPLAY 0.617021 (2025 4400);
PAINT SKYBLUE (2025 4400);
FORCEPROP 1 LAST TOLERANCE 10%
J 2
(2025 4300);
DISPLAY 0.617021 (2025 4300);
PAINT SKYBLUE (2025 4300);
FORCEPROP 1 LAST PACK_TYPE 0402
J 2
(2025 4150);
DISPLAY 0.617021 (2025 4150);
PAINT SKYBLUE (2025 4150);
FORCEPROP 1 LAST VOLTAGE 16V
J 2
(2025 4350);
DISPLAY 0.617021 (2025 4350);
PAINT SKYBLUE (2025 4350);
FORCEPROP 1 LAST MATERIAL X7R
J 2
(2025 4250);
DISPLAY 0.617021 (2025 4250);
PAINT SKYBLUE (2025 4250);
FORCEPROP 1 LASTPIN (2075 4250) $PN 2
J 2
(2065 4230);
DISPLAY 0.617021 (2065 4230);
PAINT ORANGE (2065 4230);
FORCEPROP 1 LASTPIN (2075 4450) $PN 1
J 2
(2065 4430);
DISPLAY 0.617021 (2065 4430);
PAINT ORANGE (2065 4430);
FORCEPROP 2 LAST CDS_LIB mstr_discrete
J 0
(2075 4350);
PAINT ORANGE (2075 4350);
DISPLAY INVISIBLE (2075 4350);
FORCEPROP 2 LAST SEC_TYPE 0402
J 0
(2025 4550);
DISPLAY 1.021277 (2025 4550);
PAINT ORANGE (2025 4550);
DISPLAY INVISIBLE (2025 4550);
FORCEPROP 2 LAST SEC 1
J 0
(2025 4550);
DISPLAY 0.680851 (2025 4550);
PAINT MONO (2025 4550);
DISPLAY INVISIBLE (2025 4550);
FORCEPROP 2 LAST CDS_LOCATION C8G8
J 2
(2025 4450);
DISPLAY 0.617021 (2025 4450);
PAINT AQUA (2025 4450);
DISPLAY INVISIBLE (2025 4450);
FORCEPROP 1 LAST PATH I76
J 2
(2025 4500);
DISPLAY 0.978723 (2025 4500);
PAINT WHITE (2025 4500);
DISPLAY INVISIBLE (2025 4500);
FORCEPROP 2 LAST ROOM OCP_STEERING
J 2
(2075 4350);
PAINT MONO (2075 4350);
DISPLAY INVISIBLE (2075 4350);
FORCEADD OFFPAGE..1
(-925 4950);
FORCEPROP 2 LAST $XR0 31 
J 0
(-1176 4950);
DISPLAY 0.638298 (-1176 4950);
PAINT MONO (-1176 4950);
FORCEPROP 2 LAST CDS_LIB mstr_standard
J 0
(-925 4950);
PAINT ORANGE (-925 4950);
DISPLAY INVISIBLE (-925 4950);
FORCEPROP 1 LAST OFFPAGE TRUE
J 0
(-605 4820);
PAINT GREEN (-605 4820);
DISPLAY INVISIBLE (-605 4820);
FORCEPROP 1 LAST COMMENT_BODY TRUE
J 0
(-805 4850);
DISPLAY 2.276596 (-805 4850);
PAINT GREEN (-805 4850);
DISPLAY INVISIBLE (-805 4850);
FORCEPROP 2 LAST PATH I77
J 0
(-1125 5000);
DISPLAY 1.021277 (-1125 5000);
PAINT ORANGE (-1125 5000);
DISPLAY INVISIBLE (-1125 5000);
FORCEADD TAP..3
(-750 4900);
FORCEPROP 3 LASTPIN (-750 4850) SIG_NAME P3E_CPU0_PE2_SS_TXP<15>
J 0
(-740 4860);
DISPLAY 0.659574 (-740 4860);
PAINT MONO (-740 4860);
DISPLAY INVISIBLE (-740 4860);
FORCEPROP 1 LASTPIN (-750 4850) BN 15
R 1
J 0
(-757 4838);
DISPLAY 0.617021 (-757 4838);
PAINT GREEN (-757 4838);
FORCEPROP 2 LAST CDS_LIB mstr_standard
J 0
(-750 4900);
PAINT ORANGE (-750 4900);
DISPLAY INVISIBLE (-750 4900);
FORCEPROP 1 LAST BODY_TYPE PLUMBING
J 0
(-700 4850);
DISPLAY 2.276596 (-700 4850);
PAINT GREEN (-700 4850);
DISPLAY INVISIBLE (-700 4850);
FORCEPROP 1 LAST HDL_TAP TRUE
J 0
(-430 4770);
DISPLAY 2.276596 (-430 4770);
PAINT GREEN (-430 4770);
DISPLAY INVISIBLE (-430 4770);
FORCEPROP 1 LAST PATH I78
J 0
(-752 4900);
DISPLAY 0.872340 (-752 4900);
PAINT GREEN (-752 4900);
DISPLAY INVISIBLE (-752 4900);
FORCEADD TAP..3
(-550 4900);
FORCEPROP 3 LASTPIN (-550 4850) SIG_NAME P3E_CPU0_PE2_SS_TXP<14>
J 0
(-540 4860);
DISPLAY 0.659574 (-540 4860);
PAINT MONO (-540 4860);
DISPLAY INVISIBLE (-540 4860);
FORCEPROP 1 LASTPIN (-550 4850) BN 14
R 1
J 0
(-557 4838);
DISPLAY 0.617021 (-557 4838);
PAINT GREEN (-557 4838);
FORCEPROP 2 LAST CDS_LIB mstr_standard
J 0
(-550 4900);
PAINT ORANGE (-550 4900);
DISPLAY INVISIBLE (-550 4900);
FORCEPROP 1 LAST BODY_TYPE PLUMBING
J 0
(-500 4850);
DISPLAY 2.276596 (-500 4850);
PAINT GREEN (-500 4850);
DISPLAY INVISIBLE (-500 4850);
FORCEPROP 1 LAST HDL_TAP TRUE
J 0
(-230 4770);
DISPLAY 2.276596 (-230 4770);
PAINT GREEN (-230 4770);
DISPLAY INVISIBLE (-230 4770);
FORCEPROP 1 LAST PATH I79
J 0
(-552 4900);
DISPLAY 0.872340 (-552 4900);
PAINT GREEN (-552 4900);
DISPLAY INVISIBLE (-552 4900);
FORCEADD CAP..1
R 2
(-300 3350);
FORCEPROP 1 LAST LOCATION C7G10
J 2
(-350 3450);
DISPLAY 0.617021 (-350 3450);
PAINT AQUA (-350 3450);
FORCEPROP 1 LAST PART_NUMBER A36096-155
J 2
(-350 3200);
DISPLAY 0.617021 (-350 3200);
PAINT BLUE (-350 3200);
FORCEPROP 1 LAST VALUE 0.22UF
J 2
(-350 3400);
DISPLAY 0.617021 (-350 3400);
PAINT SKYBLUE (-350 3400);
FORCEPROP 1 LAST TOLERANCE 10%
J 2
(-350 3300);
DISPLAY 0.617021 (-350 3300);
PAINT SKYBLUE (-350 3300);
FORCEPROP 1 LAST PACK_TYPE 0402
J 2
(-350 3150);
DISPLAY 0.617021 (-350 3150);
PAINT SKYBLUE (-350 3150);
FORCEPROP 1 LAST VOLTAGE 16V
J 2
(-350 3350);
DISPLAY 0.617021 (-350 3350);
PAINT SKYBLUE (-350 3350);
FORCEPROP 1 LAST MATERIAL X7R
J 2
(-350 3250);
DISPLAY 0.617021 (-350 3250);
PAINT SKYBLUE (-350 3250);
FORCEPROP 1 LASTPIN (-300 3250) $PN 2
J 2
(-310 3230);
DISPLAY 0.617021 (-310 3230);
PAINT ORANGE (-310 3230);
FORCEPROP 1 LASTPIN (-300 3450) $PN 1
J 2
(-310 3430);
DISPLAY 0.617021 (-310 3430);
PAINT ORANGE (-310 3430);
FORCEPROP 2 LAST SEC_TYPE 0402
J 0
(-350 3550);
DISPLAY 1.021277 (-350 3550);
PAINT ORANGE (-350 3550);
DISPLAY INVISIBLE (-350 3550);
FORCEPROP 2 LAST CDS_LIB mstr_discrete
J 0
(-300 3350);
PAINT ORANGE (-300 3350);
DISPLAY INVISIBLE (-300 3350);
FORCEPROP 2 LAST SEC 1
J 0
(-350 3550);
DISPLAY 0.680851 (-350 3550);
PAINT MONO (-350 3550);
DISPLAY INVISIBLE (-350 3550);
FORCEPROP 2 LAST CDS_LOCATION C7G10
J 2
(-350 3450);
DISPLAY 0.617021 (-350 3450);
PAINT AQUA (-350 3450);
DISPLAY INVISIBLE (-350 3450);
FORCEPROP 1 LAST PATH I8
J 2
(-350 3500);
DISPLAY 0.978723 (-350 3500);
PAINT WHITE (-350 3500);
DISPLAY INVISIBLE (-350 3500);
FORCEPROP 2 LAST ROOM OCP_STEERING
J 2
(-300 3350);
PAINT MONO (-300 3350);
DISPLAY INVISIBLE (-300 3350);
FORCEADD TAP..3
(-350 4900);
FORCEPROP 3 LASTPIN (-350 4850) SIG_NAME P3E_CPU0_PE2_SS_TXP<13>
J 0
(-340 4860);
DISPLAY 0.659574 (-340 4860);
PAINT MONO (-340 4860);
DISPLAY INVISIBLE (-340 4860);
FORCEPROP 1 LASTPIN (-350 4850) BN 13
R 1
J 0
(-357 4838);
DISPLAY 0.617021 (-357 4838);
PAINT GREEN (-357 4838);
FORCEPROP 2 LAST CDS_LIB mstr_standard
J 0
(-350 4900);
PAINT ORANGE (-350 4900);
DISPLAY INVISIBLE (-350 4900);
FORCEPROP 1 LAST BODY_TYPE PLUMBING
J 0
(-300 4850);
DISPLAY 2.276596 (-300 4850);
PAINT GREEN (-300 4850);
DISPLAY INVISIBLE (-300 4850);
FORCEPROP 1 LAST HDL_TAP TRUE
J 0
(-30 4770);
DISPLAY 2.276596 (-30 4770);
PAINT GREEN (-30 4770);
DISPLAY INVISIBLE (-30 4770);
FORCEPROP 1 LAST PATH I80
J 0
(-352 4900);
DISPLAY 0.872340 (-352 4900);
PAINT GREEN (-352 4900);
DISPLAY INVISIBLE (-352 4900);
FORCEADD TAP..3
(-150 4900);
FORCEPROP 3 LASTPIN (-150 4850) SIG_NAME P3E_CPU0_PE2_SS_TXP<12>
J 0
(-140 4860);
DISPLAY 0.659574 (-140 4860);
PAINT MONO (-140 4860);
DISPLAY INVISIBLE (-140 4860);
FORCEPROP 1 LASTPIN (-150 4850) BN 12
R 1
J 0
(-157 4838);
DISPLAY 0.617021 (-157 4838);
PAINT GREEN (-157 4838);
FORCEPROP 2 LAST CDS_LIB mstr_standard
J 0
(-150 4900);
PAINT ORANGE (-150 4900);
DISPLAY INVISIBLE (-150 4900);
FORCEPROP 1 LAST BODY_TYPE PLUMBING
J 0
(-100 4850);
DISPLAY 2.276596 (-100 4850);
PAINT GREEN (-100 4850);
DISPLAY INVISIBLE (-100 4850);
FORCEPROP 1 LAST HDL_TAP TRUE
J 0
(170 4770);
DISPLAY 2.276596 (170 4770);
PAINT GREEN (170 4770);
DISPLAY INVISIBLE (170 4770);
FORCEPROP 1 LAST PATH I81
J 0
(-152 4900);
DISPLAY 0.872340 (-152 4900);
PAINT GREEN (-152 4900);
DISPLAY INVISIBLE (-152 4900);
FORCEADD TAP..3
(450 4900);
FORCEPROP 3 LASTPIN (450 4850) SIG_NAME P3E_CPU0_PE2_SS_TXP<9>
J 0
(460 4860);
DISPLAY 0.659574 (460 4860);
PAINT MONO (460 4860);
DISPLAY INVISIBLE (460 4860);
FORCEPROP 1 LASTPIN (450 4850) BN 9
R 1
J 0
(443 4838);
DISPLAY 0.617021 (443 4838);
PAINT GREEN (443 4838);
FORCEPROP 2 LAST CDS_LIB mstr_standard
J 0
(450 4900);
PAINT ORANGE (450 4900);
DISPLAY INVISIBLE (450 4900);
FORCEPROP 1 LAST BODY_TYPE PLUMBING
J 0
(500 4850);
DISPLAY 2.276596 (500 4850);
PAINT GREEN (500 4850);
DISPLAY INVISIBLE (500 4850);
FORCEPROP 1 LAST HDL_TAP TRUE
J 0
(770 4770);
DISPLAY 2.276596 (770 4770);
PAINT GREEN (770 4770);
DISPLAY INVISIBLE (770 4770);
FORCEPROP 1 LAST PATH I82
J 0
(448 4900);
DISPLAY 0.872340 (448 4900);
PAINT GREEN (448 4900);
DISPLAY INVISIBLE (448 4900);
FORCEADD TAP..3
(250 4900);
FORCEPROP 3 LASTPIN (250 4850) SIG_NAME P3E_CPU0_PE2_SS_TXP<10>
J 0
(260 4860);
DISPLAY 0.659574 (260 4860);
PAINT MONO (260 4860);
DISPLAY INVISIBLE (260 4860);
FORCEPROP 1 LASTPIN (250 4850) BN 10
R 1
J 0
(243 4838);
DISPLAY 0.617021 (243 4838);
PAINT GREEN (243 4838);
FORCEPROP 2 LAST CDS_LIB mstr_standard
J 0
(250 4900);
PAINT ORANGE (250 4900);
DISPLAY INVISIBLE (250 4900);
FORCEPROP 1 LAST BODY_TYPE PLUMBING
J 0
(300 4850);
DISPLAY 2.276596 (300 4850);
PAINT GREEN (300 4850);
DISPLAY INVISIBLE (300 4850);
FORCEPROP 1 LAST HDL_TAP TRUE
J 0
(570 4770);
DISPLAY 2.276596 (570 4770);
PAINT GREEN (570 4770);
DISPLAY INVISIBLE (570 4770);
FORCEPROP 1 LAST PATH I83
J 0
(248 4900);
DISPLAY 0.872340 (248 4900);
PAINT GREEN (248 4900);
DISPLAY INVISIBLE (248 4900);
FORCEADD TAP..3
(650 4900);
FORCEPROP 3 LASTPIN (650 4850) SIG_NAME P3E_CPU0_PE2_SS_TXP<8>
J 0
(660 4860);
DISPLAY 0.659574 (660 4860);
PAINT MONO (660 4860);
DISPLAY INVISIBLE (660 4860);
FORCEPROP 1 LASTPIN (650 4850) BN 8
R 1
J 0
(643 4838);
DISPLAY 0.617021 (643 4838);
PAINT GREEN (643 4838);
FORCEPROP 2 LAST CDS_LIB mstr_standard
J 0
(650 4900);
PAINT ORANGE (650 4900);
DISPLAY INVISIBLE (650 4900);
FORCEPROP 1 LAST BODY_TYPE PLUMBING
J 0
(700 4850);
DISPLAY 2.276596 (700 4850);
PAINT GREEN (700 4850);
DISPLAY INVISIBLE (700 4850);
FORCEPROP 1 LAST HDL_TAP TRUE
J 0
(970 4770);
DISPLAY 2.276596 (970 4770);
PAINT GREEN (970 4770);
DISPLAY INVISIBLE (970 4770);
FORCEPROP 1 LAST PATH I84
J 0
(648 4900);
DISPLAY 0.872340 (648 4900);
PAINT GREEN (648 4900);
DISPLAY INVISIBLE (648 4900);
FORCEADD TAP..3
(875 4900);
FORCEPROP 3 LASTPIN (875 4850) SIG_NAME P3E_CPU0_PE2_SS_TXP<7>
J 0
(885 4860);
DISPLAY 0.659574 (885 4860);
PAINT MONO (885 4860);
DISPLAY INVISIBLE (885 4860);
FORCEPROP 1 LASTPIN (875 4850) BN 7
R 1
J 0
(868 4838);
DISPLAY 0.617021 (868 4838);
PAINT GREEN (868 4838);
FORCEPROP 2 LAST CDS_LIB mstr_standard
J 0
(875 4900);
PAINT ORANGE (875 4900);
DISPLAY INVISIBLE (875 4900);
FORCEPROP 1 LAST BODY_TYPE PLUMBING
J 0
(925 4850);
DISPLAY 2.276596 (925 4850);
PAINT GREEN (925 4850);
DISPLAY INVISIBLE (925 4850);
FORCEPROP 1 LAST HDL_TAP TRUE
J 0
(1195 4770);
DISPLAY 2.276596 (1195 4770);
PAINT GREEN (1195 4770);
DISPLAY INVISIBLE (1195 4770);
FORCEPROP 1 LAST PATH I85
J 0
(873 4900);
DISPLAY 0.872340 (873 4900);
PAINT GREEN (873 4900);
DISPLAY INVISIBLE (873 4900);
FORCEADD TAP..3
(1075 4900);
FORCEPROP 3 LASTPIN (1075 4850) SIG_NAME P3E_CPU0_PE2_SS_TXP<6>
J 0
(1085 4860);
DISPLAY 0.659574 (1085 4860);
PAINT MONO (1085 4860);
DISPLAY INVISIBLE (1085 4860);
FORCEPROP 1 LASTPIN (1075 4850) BN 6
R 1
J 0
(1068 4838);
DISPLAY 0.617021 (1068 4838);
PAINT GREEN (1068 4838);
FORCEPROP 2 LAST CDS_LIB mstr_standard
J 0
(1075 4900);
PAINT ORANGE (1075 4900);
DISPLAY INVISIBLE (1075 4900);
FORCEPROP 1 LAST BODY_TYPE PLUMBING
J 0
(1125 4850);
DISPLAY 2.276596 (1125 4850);
PAINT GREEN (1125 4850);
DISPLAY INVISIBLE (1125 4850);
FORCEPROP 1 LAST HDL_TAP TRUE
J 0
(1395 4770);
DISPLAY 2.276596 (1395 4770);
PAINT GREEN (1395 4770);
DISPLAY INVISIBLE (1395 4770);
FORCEPROP 1 LAST PATH I86
J 0
(1073 4900);
DISPLAY 0.872340 (1073 4900);
PAINT GREEN (1073 4900);
DISPLAY INVISIBLE (1073 4900);
FORCEADD TAP..3
(1275 4900);
FORCEPROP 3 LASTPIN (1275 4850) SIG_NAME P3E_CPU0_PE2_SS_TXP<5>
J 0
(1285 4860);
DISPLAY 0.659574 (1285 4860);
PAINT MONO (1285 4860);
DISPLAY INVISIBLE (1285 4860);
FORCEPROP 1 LASTPIN (1275 4850) BN 5
R 1
J 0
(1268 4838);
DISPLAY 0.617021 (1268 4838);
PAINT GREEN (1268 4838);
FORCEPROP 2 LAST CDS_LIB mstr_standard
J 0
(1275 4900);
PAINT ORANGE (1275 4900);
DISPLAY INVISIBLE (1275 4900);
FORCEPROP 1 LAST BODY_TYPE PLUMBING
J 0
(1325 4850);
DISPLAY 2.276596 (1325 4850);
PAINT GREEN (1325 4850);
DISPLAY INVISIBLE (1325 4850);
FORCEPROP 1 LAST HDL_TAP TRUE
J 0
(1595 4770);
DISPLAY 2.276596 (1595 4770);
PAINT GREEN (1595 4770);
DISPLAY INVISIBLE (1595 4770);
FORCEPROP 1 LAST PATH I87
J 0
(1273 4900);
DISPLAY 0.872340 (1273 4900);
PAINT GREEN (1273 4900);
DISPLAY INVISIBLE (1273 4900);
FORCEADD TAP..3
(1475 4900);
FORCEPROP 3 LASTPIN (1475 4850) SIG_NAME P3E_CPU0_PE2_SS_TXP<4>
J 0
(1485 4860);
DISPLAY 0.659574 (1485 4860);
PAINT MONO (1485 4860);
DISPLAY INVISIBLE (1485 4860);
FORCEPROP 1 LASTPIN (1475 4850) BN 4
R 1
J 0
(1468 4838);
DISPLAY 0.617021 (1468 4838);
PAINT GREEN (1468 4838);
FORCEPROP 2 LAST CDS_LIB mstr_standard
J 0
(1475 4900);
PAINT ORANGE (1475 4900);
DISPLAY INVISIBLE (1475 4900);
FORCEPROP 1 LAST BODY_TYPE PLUMBING
J 0
(1525 4850);
DISPLAY 2.276596 (1525 4850);
PAINT GREEN (1525 4850);
DISPLAY INVISIBLE (1525 4850);
FORCEPROP 1 LAST HDL_TAP TRUE
J 0
(1795 4770);
DISPLAY 2.276596 (1795 4770);
PAINT GREEN (1795 4770);
DISPLAY INVISIBLE (1795 4770);
FORCEPROP 1 LAST PATH I88
J 0
(1473 4900);
DISPLAY 0.872340 (1473 4900);
PAINT GREEN (1473 4900);
DISPLAY INVISIBLE (1473 4900);
FORCEADD TAP..3
(1675 4900);
FORCEPROP 3 LASTPIN (1675 4850) SIG_NAME P3E_CPU0_PE2_SS_TXP<3>
J 0
(1685 4860);
DISPLAY 0.659574 (1685 4860);
PAINT MONO (1685 4860);
DISPLAY INVISIBLE (1685 4860);
FORCEPROP 1 LASTPIN (1675 4850) BN 3
R 1
J 0
(1668 4838);
DISPLAY 0.617021 (1668 4838);
PAINT GREEN (1668 4838);
FORCEPROP 2 LAST CDS_LIB mstr_standard
J 0
(1675 4900);
PAINT ORANGE (1675 4900);
DISPLAY INVISIBLE (1675 4900);
FORCEPROP 1 LAST BODY_TYPE PLUMBING
J 0
(1725 4850);
DISPLAY 2.276596 (1725 4850);
PAINT GREEN (1725 4850);
DISPLAY INVISIBLE (1725 4850);
FORCEPROP 1 LAST HDL_TAP TRUE
J 0
(1995 4770);
DISPLAY 2.276596 (1995 4770);
PAINT GREEN (1995 4770);
DISPLAY INVISIBLE (1995 4770);
FORCEPROP 1 LAST PATH I89
J 0
(1673 4900);
DISPLAY 0.872340 (1673 4900);
PAINT GREEN (1673 4900);
DISPLAY INVISIBLE (1673 4900);
FORCEADD TAP..7
(-300 3100);
FORCEPROP 3 LASTPIN (-300 3150) SIG_NAME P3E_CPU0_PE2_SS_C_TXN<13>
J 0
(-290 3160);
DISPLAY 0.659574 (-290 3160);
PAINT MONO (-290 3160);
DISPLAY INVISIBLE (-290 3160);
FORCEPROP 1 LASTPIN (-300 3150) BN 13
R 1
J 0
(-307 3098);
DISPLAY 0.617021 (-307 3098);
PAINT GREEN (-307 3098);
FORCEPROP 2 LAST CDS_LIB mstr_standard
J 0
(-300 3100);
PAINT ORANGE (-300 3100);
DISPLAY INVISIBLE (-300 3100);
FORCEPROP 1 LAST BODY_TYPE PLUMBING
J 0
(-250 3100);
DISPLAY 2.276596 (-250 3100);
PAINT GREEN (-250 3100);
DISPLAY INVISIBLE (-250 3100);
FORCEPROP 1 LAST HDL_TAP TRUE
J 0
(20 2970);
DISPLAY 2.276596 (20 2970);
PAINT GREEN (20 2970);
DISPLAY INVISIBLE (20 2970);
FORCEPROP 1 LAST PATH I9
J 0
(-302 3100);
DISPLAY 0.872340 (-302 3100);
PAINT GREEN (-302 3100);
DISPLAY INVISIBLE (-302 3100);
FORCEADD TAP..3
(1875 4900);
FORCEPROP 3 LASTPIN (1875 4850) SIG_NAME P3E_CPU0_PE2_SS_TXP<2>
J 0
(1885 4860);
DISPLAY 0.659574 (1885 4860);
PAINT MONO (1885 4860);
DISPLAY INVISIBLE (1885 4860);
FORCEPROP 1 LASTPIN (1875 4850) BN 2
R 1
J 0
(1868 4838);
DISPLAY 0.617021 (1868 4838);
PAINT GREEN (1868 4838);
FORCEPROP 2 LAST CDS_LIB mstr_standard
J 0
(1875 4900);
PAINT ORANGE (1875 4900);
DISPLAY INVISIBLE (1875 4900);
FORCEPROP 1 LAST BODY_TYPE PLUMBING
J 0
(1925 4850);
DISPLAY 2.276596 (1925 4850);
PAINT GREEN (1925 4850);
DISPLAY INVISIBLE (1925 4850);
FORCEPROP 1 LAST HDL_TAP TRUE
J 0
(2195 4770);
DISPLAY 2.276596 (2195 4770);
PAINT GREEN (2195 4770);
DISPLAY INVISIBLE (2195 4770);
FORCEPROP 1 LAST PATH I90
J 0
(1873 4900);
DISPLAY 0.872340 (1873 4900);
PAINT GREEN (1873 4900);
DISPLAY INVISIBLE (1873 4900);
FORCEADD TAP..3
(2075 4900);
FORCEPROP 3 LASTPIN (2075 4850) SIG_NAME P3E_CPU0_PE2_SS_TXP<1>
J 0
(2085 4860);
DISPLAY 0.659574 (2085 4860);
PAINT MONO (2085 4860);
DISPLAY INVISIBLE (2085 4860);
FORCEPROP 1 LASTPIN (2075 4850) BN 1
R 1
J 0
(2068 4838);
DISPLAY 0.617021 (2068 4838);
PAINT GREEN (2068 4838);
FORCEPROP 2 LAST CDS_LIB mstr_standard
J 0
(2075 4900);
PAINT ORANGE (2075 4900);
DISPLAY INVISIBLE (2075 4900);
FORCEPROP 1 LAST BODY_TYPE PLUMBING
J 0
(2125 4850);
DISPLAY 2.276596 (2125 4850);
PAINT GREEN (2125 4850);
DISPLAY INVISIBLE (2125 4850);
FORCEPROP 1 LAST HDL_TAP TRUE
J 0
(2395 4770);
DISPLAY 2.276596 (2395 4770);
PAINT GREEN (2395 4770);
DISPLAY INVISIBLE (2395 4770);
FORCEPROP 1 LAST PATH I91
J 0
(2073 4900);
DISPLAY 0.872340 (2073 4900);
PAINT GREEN (2073 4900);
DISPLAY INVISIBLE (2073 4900);
FORCEADD TAP..3
(2275 4900);
FORCEPROP 3 LASTPIN (2275 4850) SIG_NAME P3E_CPU0_PE2_SS_TXP<0>
J 0
(2285 4860);
DISPLAY 0.659574 (2285 4860);
PAINT MONO (2285 4860);
DISPLAY INVISIBLE (2285 4860);
FORCEPROP 1 LASTPIN (2275 4850) BN 0
R 1
J 0
(2268 4838);
DISPLAY 0.617021 (2268 4838);
PAINT GREEN (2268 4838);
FORCEPROP 2 LAST CDS_LIB mstr_standard
J 0
(2275 4900);
PAINT ORANGE (2275 4900);
DISPLAY INVISIBLE (2275 4900);
FORCEPROP 1 LAST BODY_TYPE PLUMBING
J 0
(2325 4850);
DISPLAY 2.276596 (2325 4850);
PAINT GREEN (2325 4850);
DISPLAY INVISIBLE (2325 4850);
FORCEPROP 1 LAST HDL_TAP TRUE
J 0
(2595 4770);
DISPLAY 2.276596 (2595 4770);
PAINT GREEN (2595 4770);
DISPLAY INVISIBLE (2595 4770);
FORCEPROP 1 LAST PATH I92
J 0
(2273 4900);
DISPLAY 0.872340 (2273 4900);
PAINT GREEN (2273 4900);
DISPLAY INVISIBLE (2273 4900);
FORCEADD CAP..1
R 2
(2275 4650);
FORCEPROP 1 LAST LOCATION C8G9
J 2
(2225 4750);
DISPLAY 0.617021 (2225 4750);
PAINT AQUA (2225 4750);
FORCEPROP 1 LAST PART_NUMBER A36096-155
J 2
(2225 4500);
DISPLAY 0.617021 (2225 4500);
PAINT BLUE (2225 4500);
FORCEPROP 1 LAST VALUE 0.22UF
J 2
(2225 4700);
DISPLAY 0.617021 (2225 4700);
PAINT SKYBLUE (2225 4700);
FORCEPROP 1 LAST TOLERANCE 10%
J 2
(2225 4600);
DISPLAY 0.617021 (2225 4600);
PAINT SKYBLUE (2225 4600);
FORCEPROP 1 LAST PACK_TYPE 0402
J 2
(2225 4450);
DISPLAY 0.617021 (2225 4450);
PAINT SKYBLUE (2225 4450);
FORCEPROP 1 LAST VOLTAGE 16V
J 2
(2225 4650);
DISPLAY 0.617021 (2225 4650);
PAINT SKYBLUE (2225 4650);
FORCEPROP 1 LAST MATERIAL X7R
J 2
(2225 4550);
DISPLAY 0.617021 (2225 4550);
PAINT SKYBLUE (2225 4550);
FORCEPROP 1 LASTPIN (2275 4550) $PN 2
J 2
(2265 4530);
DISPLAY 0.617021 (2265 4530);
PAINT ORANGE (2265 4530);
FORCEPROP 1 LASTPIN (2275 4750) $PN 1
J 2
(2265 4730);
DISPLAY 0.617021 (2265 4730);
PAINT ORANGE (2265 4730);
FORCEPROP 2 LAST CDS_LIB mstr_discrete
J 0
(2275 4650);
PAINT ORANGE (2275 4650);
DISPLAY INVISIBLE (2275 4650);
FORCEPROP 2 LAST SEC_TYPE 0402
J 0
(2225 4850);
DISPLAY 1.021277 (2225 4850);
PAINT ORANGE (2225 4850);
DISPLAY INVISIBLE (2225 4850);
FORCEPROP 2 LAST SEC 1
J 0
(2225 4850);
DISPLAY 0.680851 (2225 4850);
PAINT MONO (2225 4850);
DISPLAY INVISIBLE (2225 4850);
FORCEPROP 2 LAST CDS_LOCATION C8G9
J 2
(2225 4750);
DISPLAY 0.617021 (2225 4750);
PAINT AQUA (2225 4750);
DISPLAY INVISIBLE (2225 4750);
FORCEPROP 1 LAST PATH I93
J 2
(2225 4800);
DISPLAY 0.978723 (2225 4800);
PAINT WHITE (2225 4800);
DISPLAY INVISIBLE (2225 4800);
FORCEPROP 2 LAST ROOM OCP_STEERING
J 2
(2275 4650);
PAINT MONO (2275 4650);
DISPLAY INVISIBLE (2275 4650);
FORCEADD TAP..7
(2325 3100);
FORCEPROP 3 LASTPIN (2325 3150) SIG_NAME P3E_CPU0_PE2_SS_C_TXN<0>
J 0
(2335 3160);
DISPLAY 0.659574 (2335 3160);
PAINT MONO (2335 3160);
DISPLAY INVISIBLE (2335 3160);
FORCEPROP 1 LASTPIN (2325 3150) BN 0
R 1
J 0
(2318 3098);
DISPLAY 0.617021 (2318 3098);
PAINT GREEN (2318 3098);
FORCEPROP 2 LAST CDS_LIB mstr_standard
J 0
(2325 3100);
PAINT ORANGE (2325 3100);
DISPLAY INVISIBLE (2325 3100);
FORCEPROP 1 LAST BODY_TYPE PLUMBING
J 0
(2375 3100);
DISPLAY 2.276596 (2375 3100);
PAINT GREEN (2375 3100);
DISPLAY INVISIBLE (2375 3100);
FORCEPROP 1 LAST HDL_TAP TRUE
J 0
(2645 2970);
DISPLAY 2.276596 (2645 2970);
PAINT GREEN (2645 2970);
DISPLAY INVISIBLE (2645 2970);
FORCEPROP 1 LAST PATH I94
J 0
(2323 3100);
DISPLAY 0.872340 (2323 3100);
PAINT GREEN (2323 3100);
DISPLAY INVISIBLE (2323 3100);
FORCEADD OFFPAGE..2
(2550 3050);
FORCEPROP 2 LAST $XR0 109 
J 0
(2739 3050);
DISPLAY 0.638298 (2739 3050);
PAINT MONO (2739 3050);
FORCEPROP 2 LAST $XR1 245 
J 0
(2739 3050);
DISPLAY 0.638298 (2739 3050);
PAINT MONO (2739 3050);
FORCEPROP 2 LAST CDS_LIB mstr_standard
J 0
(2550 3050);
PAINT ORANGE (2550 3050);
DISPLAY INVISIBLE (2550 3050);
FORCEPROP 1 LAST OFFPAGE TRUE
J 0
(2875 2925);
DISPLAY 0.872340 (2875 2925);
PAINT GREEN (2875 2925);
DISPLAY INVISIBLE (2875 2925);
FORCEPROP 1 LAST COMMENT_BODY TRUE
J 0
(2505 2955);
DISPLAY 0.872340 (2505 2955);
PAINT GREEN (2505 2955);
DISPLAY INVISIBLE (2505 2955);
FORCEPROP 2 LAST PATH I95
J 0
(2875 3100);
DISPLAY 1.021277 (2875 3100);
PAINT ORANGE (2875 3100);
DISPLAY INVISIBLE (2875 3100);
FORCEADD CAP..1
R 2
(2325 3650);
FORCEPROP 1 LAST LOCATION C8G10
J 2
(2275 3750);
DISPLAY 0.617021 (2275 3750);
PAINT AQUA (2275 3750);
FORCEPROP 1 LAST PART_NUMBER A36096-155
J 2
(2275 3500);
DISPLAY 0.617021 (2275 3500);
PAINT BLUE (2275 3500);
FORCEPROP 1 LAST VALUE 0.22UF
J 2
(2275 3700);
DISPLAY 0.617021 (2275 3700);
PAINT SKYBLUE (2275 3700);
FORCEPROP 1 LAST TOLERANCE 10%
J 2
(2275 3600);
DISPLAY 0.617021 (2275 3600);
PAINT SKYBLUE (2275 3600);
FORCEPROP 1 LAST PACK_TYPE 0402
J 2
(2275 3450);
DISPLAY 0.617021 (2275 3450);
PAINT SKYBLUE (2275 3450);
FORCEPROP 1 LAST VOLTAGE 16V
J 2
(2275 3650);
DISPLAY 0.617021 (2275 3650);
PAINT SKYBLUE (2275 3650);
FORCEPROP 1 LAST MATERIAL X7R
J 2
(2275 3550);
DISPLAY 0.617021 (2275 3550);
PAINT SKYBLUE (2275 3550);
FORCEPROP 1 LASTPIN (2325 3550) $PN 2
J 2
(2315 3530);
DISPLAY 0.617021 (2315 3530);
PAINT ORANGE (2315 3530);
FORCEPROP 1 LASTPIN (2325 3750) $PN 1
J 2
(2315 3730);
DISPLAY 0.617021 (2315 3730);
PAINT ORANGE (2315 3730);
FORCEPROP 2 LAST CDS_LIB mstr_discrete
J 0
(2325 3650);
PAINT ORANGE (2325 3650);
DISPLAY INVISIBLE (2325 3650);
FORCEPROP 2 LAST SEC_TYPE 0402
J 0
(2275 3850);
DISPLAY 1.021277 (2275 3850);
PAINT ORANGE (2275 3850);
DISPLAY INVISIBLE (2275 3850);
FORCEPROP 2 LAST SEC 1
J 0
(2275 3850);
DISPLAY 0.680851 (2275 3850);
PAINT MONO (2275 3850);
DISPLAY INVISIBLE (2275 3850);
FORCEPROP 2 LAST CDS_LOCATION C8G10
J 2
(2275 3750);
DISPLAY 0.617021 (2275 3750);
PAINT AQUA (2275 3750);
DISPLAY INVISIBLE (2275 3750);
FORCEPROP 1 LAST PATH I96
J 2
(2275 3800);
DISPLAY 0.978723 (2275 3800);
PAINT WHITE (2275 3800);
DISPLAY INVISIBLE (2275 3800);
FORCEPROP 2 LAST ROOM OCP_STEERING
J 2
(2325 3650);
PAINT MONO (2325 3650);
DISPLAY INVISIBLE (2325 3650);
FORCEADD TAP..3
(2325 3900);
FORCEPROP 3 LASTPIN (2325 3850) SIG_NAME P3E_CPU0_PE2_SS_TXN<0>
J 0
(2335 3860);
DISPLAY 0.659574 (2335 3860);
PAINT MONO (2335 3860);
DISPLAY INVISIBLE (2335 3860);
FORCEPROP 1 LASTPIN (2325 3850) BN 0
R 1
J 0
(2318 3838);
DISPLAY 0.617021 (2318 3838);
PAINT GREEN (2318 3838);
FORCEPROP 2 LAST CDS_LIB mstr_standard
J 0
(2325 3900);
PAINT ORANGE (2325 3900);
DISPLAY INVISIBLE (2325 3900);
FORCEPROP 1 LAST BODY_TYPE PLUMBING
J 0
(2375 3850);
DISPLAY 2.276596 (2375 3850);
PAINT GREEN (2375 3850);
DISPLAY INVISIBLE (2375 3850);
FORCEPROP 1 LAST HDL_TAP TRUE
J 0
(2645 3770);
DISPLAY 2.276596 (2645 3770);
PAINT GREEN (2645 3770);
DISPLAY INVISIBLE (2645 3770);
FORCEPROP 1 LAST PATH I97
J 0
(2323 3900);
DISPLAY 0.872340 (2323 3900);
PAINT GREEN (2323 3900);
DISPLAY INVISIBLE (2323 3900);
FORCEADD TAP..7
(2275 4100);
FORCEPROP 3 LASTPIN (2275 4150) SIG_NAME P3E_CPU0_PE2_SS_C_TXP<0>
J 0
(2285 4160);
DISPLAY 0.659574 (2285 4160);
PAINT MONO (2285 4160);
DISPLAY INVISIBLE (2285 4160);
FORCEPROP 1 LASTPIN (2275 4150) BN 0
R 1
J 0
(2268 4098);
DISPLAY 0.617021 (2268 4098);
PAINT GREEN (2268 4098);
FORCEPROP 2 LAST CDS_LIB mstr_standard
J 0
(2275 4100);
PAINT ORANGE (2275 4100);
DISPLAY INVISIBLE (2275 4100);
FORCEPROP 1 LAST BODY_TYPE PLUMBING
J 0
(2325 4100);
DISPLAY 2.276596 (2325 4100);
PAINT GREEN (2325 4100);
DISPLAY INVISIBLE (2325 4100);
FORCEPROP 1 LAST HDL_TAP TRUE
J 0
(2595 3970);
DISPLAY 2.276596 (2595 3970);
PAINT GREEN (2595 3970);
DISPLAY INVISIBLE (2595 3970);
FORCEPROP 1 LAST PATH I98
J 0
(2273 4100);
DISPLAY 0.872340 (2273 4100);
PAINT GREEN (2273 4100);
DISPLAY INVISIBLE (2273 4100);
FORCEADD OFFPAGE..2
(2525 4050);
FORCEPROP 2 LAST $XR0 109 
J 0
(2714 4050);
DISPLAY 0.638298 (2714 4050);
PAINT MONO (2714 4050);
FORCEPROP 2 LAST $XR1 245 
J 0
(2714 4050);
DISPLAY 0.638298 (2714 4050);
PAINT MONO (2714 4050);
FORCEPROP 2 LAST CDS_LIB mstr_standard
J 0
(2525 4050);
PAINT ORANGE (2525 4050);
DISPLAY INVISIBLE (2525 4050);
FORCEPROP 1 LAST OFFPAGE TRUE
J 0
(2850 3925);
DISPLAY 0.872340 (2850 3925);
PAINT GREEN (2850 3925);
DISPLAY INVISIBLE (2850 3925);
FORCEPROP 1 LAST COMMENT_BODY TRUE
J 0
(2480 3955);
DISPLAY 0.872340 (2480 3955);
PAINT GREEN (2480 3955);
DISPLAY INVISIBLE (2480 3955);
FORCEPROP 2 LAST PATH I99
J 0
(2975 4100);
DISPLAY 1.021277 (2975 4100);
PAINT ORANGE (2975 4100);
DISPLAY INVISIBLE (2975 4100);
FORCEADD CAD_NOTE..1
(-2450 3825);
FORCEPROP 0 LAST L1 PLACE CLOSE TO CPU.
J 0
(-2575 3700);
DISPLAY 1.021277 (-2575 3700);
PAINT ORANGE (-2575 3700);
FORCEPROP 0 LAST L3 NEAR CPU, PLACE NEAR SLOT
J 0
(-2575 3550);
DISPLAY 1.021277 (-2575 3550);
PAINT ORANGE (-2575 3550);
FORCEPROP 0 LAST L2 IF THERE IS NOT ENOUGH ROOM
J 0
(-2575 3625);
DISPLAY 1.021277 (-2575 3625);
PAINT ORANGE (-2575 3625);
FORCEPROP 2 LAST CDS_LIB mstr_symbols
J 0
(-2450 3825);
PAINT ORANGE (-2450 3825);
DISPLAY INVISIBLE (-2450 3825);
FORCEPROP 1 LAST COMMENT_BODY TRUE
J 0
(-2425 3925);
DISPLAY 0.978723 (-2425 3925);
PAINT ORANGE (-2425 3925);
DISPLAY INVISIBLE (-2425 3925);
FORCEADD INTEL_CORP_BPAGE..1
(4350 200);
FORCEPROP 1 LAST CDS_CON_LAST_MODIFIED Tue Dec 01 11:51:52 2015
J 0
(2925 525);
PAINT ORANGE (2925 525);
DISPLAY INVISIBLE (2925 525);
FORCEPROP 1 LAST CUSTOM_TXT_CDS <CURRENT_DESIGN_SHEET> OF <TOTAL_DESIGN_SHEETS>
J 0
(3850 225);
PAINT GREEN (3850 225);
FORCEPROP 1 LAST CUSTOM_TXT_CDS <CON_LAST_MODIFIED>
J 0
(2425 550);
PAINT GREEN (2425 550);
FORCEPROP 2 LAST CUSTOM_TXT_CDS <XR_PAGE_TITLE>
J 0
(-3540 5450);
DISPLAY 0.638298 (-3540 5450);
PAINT PINK (-3540 5450);
DISPLAY INVISIBLE (-3540 5450);
FORCEPROP 1 LAST SCH_ADDRESS3 Santa Clara, CA 95052-8119
J 0
(375 225);
DISPLAY 0.617021 (375 225);
PAINT GREEN (375 225);
FORCEPROP 1 LAST SCH_ADDRESS2 P.O. BOX 58119
J 0
(375 275);
DISPLAY 0.617021 (375 275);
PAINT GREEN (375 275);
FORCEPROP 1 LAST SCH_ADDRESS1 2200 Mission College Blvd.
J 0
(375 325);
DISPLAY 0.617021 (375 325);
PAINT GREEN (375 325);
FORCEPROP 1 LAST SCH_TITLE PCIE TX CAPS
J 0
(-3600 250);
DISPLAY 1.212766 (-3600 250);
PAINT ORANGE (-3600 250);
FORCEPROP 1 LAST SCH_NUMBER H4694802
J 0
(3050 350);
DISPLAY 1.212766 (3050 350);
PAINT YELLOW (3050 350);
FORCEPROP 1 LAST SCH_DEPT BESD
J 1
(-100 300);
DISPLAY 1.212766 (-100 300);
PAINT YELLOW (-100 300);
FORCEPROP 1 LAST SCH_REV 2.420
J 0
(4100 350);
DISPLAY 0.978723 (4100 350);
PAINT YELLOW (4100 350);
FORCEPROP 2 LAST CDS_LIB mstr_symbols
J 0
(4350 200);
PAINT MONO (4350 200);
DISPLAY INVISIBLE (4350 200);
FORCEPROP 2 LAST PAGE_BORDER TRUE
J 0
(-3540 5450);
DISPLAY 0.638298 (-3540 5450);
PAINT PINK (-3540 5450);
DISPLAY INVISIBLE (-3540 5450);
FORCEPROP 1 LAST COMMENT_BODY TRUE
J 0
(4362 212);
DISPLAY 0.468085 (4362 212);
PAINT GREEN (4362 212);
DISPLAY INVISIBLE (4362 212);
FORCEPROP 2 LAST CDS_XR_PAGE_TITLE CR-105 : @BASEBOARD_FAB2_LIB.BASEBOARD_FAB2(SCH_1):PAGE105
J 0
(-3540 5450);
DISPLAY 0.638298 (-3540 5450);
PAINT PINK (-3540 5450);
DISPLAY INVISIBLE (-3540 5450);
WIRE 17 -1 (2250 4950)(2050 4950);
WIRE 17 -1 (2050 4950)(1850 4950);
WIRE 17 -1 (1850 4950)(1650 4950);
WIRE 17 -1 (1650 4950)(1450 4950);
WIRE 17 -1 (1450 4950)(1250 4950);
WIRE 17 -1 (1250 4950)(1050 4950);
WIRE 17 -1 (1050 4950)(850 4950);
WIRE 17 -1 (850 4950)(625 4950);
WIRE 17 -1 (425 4950)(625 4950);
WIRE 17 -1 (425 4950)(225 4950);
WIRE 17 -1 (225 4950)(25 4950);
FORCEPROP 2 LAST SIG_NAME P3E_CPU0_PE2_SS_TXP<15:0>
J 0
(-850 4960);
DISPLAY 0.617021 (-850 4960);
PAINT ORANGE (-850 4960);
WIRE 17 -1 (2300 4050)(2475 4050);
WIRE 17 -1 (2300 4050)(2100 4050);
FORCEPROP 2 LAST SIG_NAME P3E_CPU0_PE2_SS_C_TXP<15:0>
J 0
(1850 4010);
DISPLAY 0.617021 (1850 4010);
PAINT ORANGE (1850 4010);
WIRE 17 -1 (2100 4050)(1900 4050);
WIRE 17 -1 (1900 4050)(1700 4050);
WIRE 17 -1 (1700 4050)(1500 4050);
WIRE 17 -1 (1500 4050)(1300 4050);
WIRE 17 -1 (1300 4050)(1100 4050);
WIRE 17 -1 (1100 4050)(900 4050);
WIRE 17 -1 (900 4050)(675 4050);
WIRE 17 -1 (675 4050)(475 4050);
WIRE 17 -1 (475 4050)(275 4050);
WIRE 17 -1 (275 4050)(75 4050);
WIRE 17 -1 (75 4050)(-125 4050);
WIRE 17 -1 (-125 4050)(-325 4050);
WIRE 17 -1 (-325 4050)(-525 4050);
WIRE 17 -1 (-525 4050)(-725 4050);
WIRE 17 -1 (2300 3950)(2100 3950);
WIRE 17 -1 (2100 3950)(1900 3950);
WIRE 17 -1 (1900 3950)(1700 3950);
WIRE 17 -1 (1700 3950)(1500 3950);
WIRE 17 -1 (1500 3950)(1300 3950);
WIRE 17 -1 (1300 3950)(1100 3950);
WIRE 17 -1 (1100 3950)(900 3950);
WIRE 17 -1 (900 3950)(675 3950);
WIRE 17 -1 (475 3950)(675 3950);
WIRE 17 -1 (475 3950)(275 3950);
WIRE 17 -1 (275 3950)(75 3950);
FORCEPROP 2 LAST SIG_NAME P3E_CPU0_PE2_SS_TXN<15:0>
J 0
(-800 3960);
DISPLAY 0.617021 (-800 3960);
PAINT ORANGE (-800 3960);
WIRE 17 -1 (2500 3050)(2350 3050);
FORCEPROP 2 LAST SIG_NAME P3E_CPU0_PE2_SS_C_TXN<15:0>
J 0
(1850 3010);
DISPLAY 0.617021 (1850 3010);
PAINT ORANGE (1850 3010);
WIRE 17 -1 (2350 3050)(2150 3050);
WIRE 17 -1 (2175 2625)(2375 2625);
WIRE 17 -1 (2175 2625)(1975 2625);
WIRE 17 -1 (1975 2625)(1775 2625);
WIRE 17 -1 (1775 2625)(1575 2625);
WIRE 17 -1 (1575 2625)(1375 2625);
WIRE 17 -1 (1375 2625)(1175 2625);
WIRE 17 -1 (1175 2625)(975 2625);
WIRE 17 -1 (975 2625)(875 2625);
FORCEPROP 2 LAST SIG_NAME P3E_CPU0_PE1_PCH_R_RXP<15:8>
J 0
(915 2635);
DISPLAY 0.617021 (915 2635);
PAINT ORANGE (915 2635);
WIRE 17 -1 (2650 1725)(2425 1725);
WIRE 17 -1 (2425 1725)(2225 1725);
WIRE 17 -1 (2225 1725)(2025 1725);
WIRE 17 -1 (2025 1725)(1825 1725);
FORCEPROP 2 LAST SIG_NAME P3E_CPU0_PE1_PCH_RXP<15:8>
J 0
(1865 1685);
DISPLAY 0.617021 (1865 1685);
PAINT ORANGE (1865 1685);
WIRE 17 -1 (2225 1625)(2425 1625);
WIRE 17 -1 (2225 1625)(2025 1625);
WIRE 17 -1 (2025 1625)(1825 1625);
WIRE 17 -1 (1825 1625)(1625 1625);
WIRE 17 -1 (1625 1625)(1425 1625);
WIRE 17 -1 (1425 1625)(1225 1625);
WIRE 17 -1 (1225 1625)(1025 1625);
WIRE 17 -1 (1025 1625)(925 1625);
FORCEPROP 2 LAST SIG_NAME P3E_CPU0_PE1_PCH_R_RXN<15:8>
J 0
(965 1635);
DISPLAY 0.617021 (965 1635);
PAINT ORANGE (965 1635);
WIRE 17 -1 (2275 725)(2075 725);
WIRE 17 -1 (2475 725)(2275 725);
WIRE 17 -1 (2075 725)(1875 725);
WIRE 17 -1 (1875 725)(1675 725);
FORCEPROP 2 LAST SIG_NAME P3E_CPU0_PE1_PCH_RXN<15:8>
J 0
(1815 685);
DISPLAY 0.617021 (1815 685);
PAINT ORANGE (1815 685);
WIRE 17 -1 (2700 725)(2475 725);
WIRE 17 -1 (2150 3050)(1950 3050);
WIRE 17 -1 (1950 3050)(1750 3050);
WIRE 17 -1 (1750 3050)(1550 3050);
WIRE 17 -1 (1550 3050)(1350 3050);
WIRE 17 -1 (1350 3050)(1150 3050);
WIRE 17 -1 (1150 3050)(950 3050);
WIRE 17 -1 (950 3050)(725 3050);
WIRE 17 -1 (725 3050)(525 3050);
WIRE 17 -1 (525 3050)(325 3050);
WIRE 17 -1 (325 3050)(125 3050);
WIRE 17 -1 (125 3050)(-75 3050);
WIRE 17 -1 (-75 3050)(-275 3050);
WIRE 17 -1 (-275 3050)(-475 3050);
WIRE 17 -1 (-675 3050)(-475 3050);
WIRE 17 -1 (1425 1725)(1225 1725);
WIRE 17 -1 (1625 1725)(1425 1725);
WIRE 17 -1 (1225 1725)(1025 1725);
WIRE 17 -1 (1825 1725)(1625 1725);
WIRE 17 -1 (1475 725)(1275 725);
WIRE 17 -1 (1675 725)(1475 725);
WIRE 17 -1 (1075 725)(1275 725);
WIRE 17 -1 (25 4950)(-175 4950);
WIRE 17 -1 (-175 4950)(-375 4950);
WIRE 17 -1 (-375 4950)(-575 4950);
WIRE 17 -1 (-575 4950)(-775 4950);
WIRE 17 -1 (-775 4950)(-875 4950);
WIRE 17 -1 (75 3950)(-125 3950);
WIRE 17 -1 (-325 3950)(-525 3950);
WIRE 17 -1 (-125 3950)(-325 3950);
WIRE 17 -1 (-525 3950)(-725 3950);
WIRE 17 -1 (-725 3950)(-825 3950);
WIRE 17 -1 (-1575 2575)(-1375 2575);
WIRE 17 -1 (-1575 2575)(-1775 2575);
WIRE 17 -1 (-1775 2575)(-1975 2575);
WIRE 17 -1 (-1975 2575)(-2175 2575);
WIRE 17 -1 (-2175 2575)(-2375 2575);
WIRE 17 -1 (-2375 2575)(-2575 2575);
WIRE 17 -1 (-2575 2575)(-2775 2575);
WIRE 17 -1 (-2775 2575)(-2875 2575);
FORCEPROP 2 LAST SIG_NAME P3E_CPU0_PE1_PCH_TXN<15:8>
J 0
(-2860 2585);
DISPLAY 0.617021 (-2860 2585);
PAINT ORANGE (-2860 2585);
WIRE 17 -1 (-1525 1675)(-1725 1675);
WIRE 17 -1 (-1325 1675)(-1525 1675);
WIRE 17 -1 (-1725 1675)(-1925 1675);
WIRE 17 -1 (-1925 1675)(-2125 1675);
WIRE 17 -1 (-1100 1675)(-1325 1675);
FORCEPROP 0 LAST SIG_NAME P3E_CPU0_PE1_PCH_C_TXN<15:8>
J 0
(-1985 1635);
DISPLAY 0.617021 (-1985 1635);
PAINT ORANGE (-1985 1635);
WIRE 17 -1 (-1525 1575)(-1325 1575);
WIRE 17 -1 (-1525 1575)(-1725 1575);
WIRE 17 -1 (-1725 1575)(-1925 1575);
WIRE 17 -1 (-1925 1575)(-2125 1575);
WIRE 17 -1 (-2125 1575)(-2325 1575);
WIRE 17 -1 (-2325 1575)(-2525 1575);
WIRE 17 -1 (-2525 1575)(-2725 1575);
WIRE 17 -1 (-2725 1575)(-2825 1575);
FORCEPROP 2 LAST SIG_NAME P3E_CPU0_PE1_PCH_TXP<15:8>
J 0
(-2810 1585);
DISPLAY 0.617021 (-2810 1585);
PAINT ORANGE (-2810 1585);
WIRE 17 -1 (-2125 1675)(-2325 1675);
WIRE 17 -1 (-1475 675)(-1675 675);
WIRE 17 -1 (-1275 675)(-1475 675);
WIRE 17 -1 (-1675 675)(-1875 675);
WIRE 17 -1 (-1875 675)(-2075 675);
FORCEPROP 2 LAST SIG_NAME P3E_CPU0_PE1_PCH_C_TXP<15:8>
J 0
(-1985 635);
DISPLAY 0.617021 (-1985 635);
PAINT ORANGE (-1985 635);
WIRE 17 -1 (-1050 675)(-1275 675);
WIRE 17 -1 (-2325 1675)(-2525 1675);
WIRE 17 -1 (-2525 1675)(-2725 1675);
WIRE 17 -1 (-2275 675)(-2475 675);
WIRE 17 -1 (-2075 675)(-2275 675);
WIRE 17 -1 (-2675 675)(-2475 675);
WIRE 16 -1 (-2700 775)(-2700 875);
WIRE 16 -1 (-2300 775)(-2300 875);
WIRE 16 -1 (-2500 1175)(-2500 775);
WIRE 16 -1 (-2100 775)(-2100 1175);
WIRE 16 -1 (-2700 1475)(-2700 1075);
WIRE 16 -1 (-2750 1775)(-2750 1875);
WIRE 16 -1 (-2500 1475)(-2500 1375);
WIRE 16 -1 (-2300 1475)(-2300 1075);
WIRE 16 -1 (-2100 1475)(-2100 1375);
WIRE 16 -1 (-2350 1775)(-2350 1875);
WIRE 16 -1 (-2150 1775)(-2150 2175);
WIRE 16 -1 (-2550 2175)(-2550 1775);
WIRE 16 -1 (-2750 2475)(-2750 2075);
WIRE 16 -1 (-2350 2475)(-2350 2075);
WIRE 16 -1 (-2550 2475)(-2550 2375);
WIRE 16 -1 (-2150 2475)(-2150 2375);
WIRE 16 -1 (-1900 775)(-1900 875);
WIRE 16 -1 (-1500 775)(-1500 875);
WIRE 16 -1 (-1300 775)(-1300 1175);
WIRE 16 -1 (-1700 775)(-1700 1175);
WIRE 16 -1 (-1900 1475)(-1900 1075);
WIRE 16 -1 (-1700 1375)(-1700 1475);
WIRE 16 -1 (-1950 1775)(-1950 1875);
WIRE 16 -1 (-1550 1775)(-1550 1875);
WIRE 16 -1 (-1500 1075)(-1500 1475);
WIRE 16 -1 (-1300 1375)(-1300 1475);
WIRE 16 -1 (-1350 1775)(-1350 2175);
WIRE 16 -1 (-1750 1775)(-1750 2175);
WIRE 16 -1 (-1950 2475)(-1950 2075);
WIRE 16 -1 (-1550 2075)(-1550 2475);
WIRE 16 -1 (-1750 2375)(-1750 2475);
WIRE 16 -1 (-1350 2375)(-1350 2475);
WIRE 16 -1 (-700 3150)(-700 3250);
WIRE 16 -1 (-700 3850)(-700 3450);
WIRE 16 -1 (-300 3150)(-300 3250);
WIRE 16 -1 (-500 3550)(-500 3150);
WIRE 16 -1 (-100 3150)(-100 3550);
WIRE 16 -1 (-300 3850)(-300 3450);
WIRE 16 -1 (-500 3850)(-500 3750);
WIRE 16 -1 (-100 3850)(-100 3750);
WIRE 16 -1 (-750 4150)(-750 4250);
WIRE 16 -1 (-550 4550)(-550 4150);
WIRE 16 -1 (-750 4850)(-750 4450);
WIRE 16 -1 (-550 4850)(-550 4750);
WIRE 16 -1 (-350 4150)(-350 4250);
WIRE 16 -1 (-150 4150)(-150 4550);
WIRE 16 -1 (-350 4850)(-350 4450);
WIRE 16 -1 (-150 4850)(-150 4750);
WIRE 16 -1 (1000 1825)(1000 1925);
WIRE 16 -1 (1050 825)(1050 925);
WIRE 16 -1 (1450 825)(1450 925);
WIRE 16 -1 (1850 825)(1850 925);
WIRE 16 -1 (1650 825)(1650 1225);
WIRE 16 -1 (1250 1225)(1250 825);
WIRE 16 -1 (1050 1525)(1050 1125);
WIRE 16 -1 (1250 1525)(1250 1425);
WIRE 16 -1 (1450 1525)(1450 1125);
WIRE 16 -1 (1400 1825)(1400 1925);
WIRE 16 -1 (1650 1525)(1650 1425);
WIRE 16 -1 (1850 1525)(1850 1125);
WIRE 16 -1 (1800 1825)(1800 1925);
WIRE 16 -1 (1600 1825)(1600 2225);
WIRE 16 -1 (1200 2225)(1200 1825);
WIRE 16 -1 (2000 1825)(2000 2225);
WIRE 16 -1 (1000 2525)(1000 2125);
WIRE 16 -1 (100 3150)(100 3250);
WIRE 16 -1 (500 3150)(500 3250);
WIRE 16 -1 (300 3150)(300 3550);
WIRE 16 -1 (500 3450)(500 3850);
WIRE 16 -1 (100 3850)(100 3450);
WIRE 16 -1 (300 3750)(300 3850);
WIRE 16 -1 (700 3150)(700 3550);
WIRE 16 -1 (925 3150)(925 3250);
WIRE 16 -1 (925 3850)(925 3450);
WIRE 16 -1 (700 3750)(700 3850);
WIRE 16 -1 (1200 2525)(1200 2425);
WIRE 16 -1 (1400 2525)(1400 2125);
WIRE 16 -1 (1600 2525)(1600 2425);
WIRE 16 -1 (1800 2525)(1800 2125);
WIRE 16 -1 (2000 2425)(2000 2525);
WIRE 16 -1 (1125 3550)(1125 3150);
WIRE 16 -1 (1325 3150)(1325 3250);
WIRE 16 -1 (1525 3150)(1525 3550);
WIRE 16 -1 (1325 3850)(1325 3450);
WIRE 16 -1 (1125 3850)(1125 3750);
WIRE 16 -1 (1525 3850)(1525 3750);
WIRE 16 -1 (1725 3150)(1725 3250);
WIRE 16 -1 (1925 3150)(1925 3550);
WIRE 16 -1 (1725 3850)(1725 3450);
WIRE 16 -1 (1925 3750)(1925 3850);
WIRE 16 -1 (2250 825)(2250 925);
WIRE 16 -1 (2450 825)(2450 1225);
WIRE 16 -1 (2050 825)(2050 1225);
WIRE 16 -1 (2250 1125)(2250 1525);
WIRE 16 -1 (2050 1425)(2050 1525);
WIRE 16 -1 (2450 1425)(2450 1525);
WIRE 16 -1 (2200 1825)(2200 1925);
WIRE 16 -1 (2400 1825)(2400 2225);
WIRE 16 -1 (2200 2125)(2200 2525);
WIRE 16 -1 (2400 2425)(2400 2525);
WIRE 16 -1 (2125 3150)(2125 3250);
WIRE 16 -1 (2325 3150)(2325 3550);
WIRE 16 -1 (2125 3450)(2125 3850);
WIRE 16 -1 (2325 3750)(2325 3850);
WIRE 16 -1 (50 4150)(50 4250);
WIRE 16 -1 (250 4150)(250 4550);
WIRE 16 -1 (450 4150)(450 4250);
WIRE 16 -1 (450 4450)(450 4850);
WIRE 16 -1 (50 4850)(50 4450);
WIRE 16 -1 (250 4750)(250 4850);
WIRE 16 -1 (650 4150)(650 4550);
WIRE 16 -1 (875 4150)(875 4250);
WIRE 16 -1 (875 4850)(875 4450);
WIRE 16 -1 (650 4750)(650 4850);
WIRE 16 -1 (1275 4150)(1275 4250);
WIRE 16 -1 (1075 4550)(1075 4150);
WIRE 16 -1 (1475 4150)(1475 4550);
WIRE 16 -1 (1275 4850)(1275 4450);
WIRE 16 -1 (1075 4850)(1075 4750);
WIRE 16 -1 (1475 4850)(1475 4750);
WIRE 16 -1 (1675 4150)(1675 4250);
WIRE 16 -1 (1875 4150)(1875 4550);
WIRE 16 -1 (1675 4850)(1675 4450);
WIRE 16 -1 (1875 4750)(1875 4850);
WIRE 16 -1 (2075 4150)(2075 4250);
WIRE 16 -1 (2275 4150)(2275 4550);
WIRE 16 -1 (2075 4450)(2075 4850);
WIRE 16 -1 (2275 4750)(2275 4850);
FORCENOTE
TO X24 SLOT
(2825 3750) 0;
DISPLAY LEFT (2825 3750);
DISPLAY 1.021277 (2825 3750);
PAINT PURPLE (2825 3750);
FORCENOTE
TO CPU0
(3100 1875) 0;
DISPLAY LEFT (3100 1875);
DISPLAY 1.021277 (3100 1875);
PAINT PURPLE (3100 1875);
FORCENOTE
PCH PCIEUP TO CPU0 RX CAPS
(1425 2700) 0;
DISPLAY LEFT (1425 2700);
DISPLAY 1.021277 (1425 2700);
PAINT PURPLE (1425 2700);
FORCENOTE
DE NOTE:
(1425 2775) 0;
DISPLAY LEFT (1425 2775);
DISPLAY 1.021277 (1425 2775);
PAINT PURPLE (1425 2775);
FORCENOTE
FROM PCH PCIEUP
(50 1800) 0;
DISPLAY LEFT (50 1800);
DISPLAY 1.021277 (50 1800);
PAINT PURPLE (50 1800);
FORCENOTE
DE NOTE:
(-100 5100) 0;
DISPLAY LEFT (-100 5100);
DISPLAY 1.021277 (-100 5100);
PAINT PURPLE (-100 5100);
FORCENOTE
CPU0 TO PCIE X24 SLOT TX CAPS
(-100 5025) 0;
DISPLAY LEFT (-100 5025);
DISPLAY 1.021277 (-100 5025);
PAINT PURPLE (-100 5025);
FORCENOTE
FROM CPU0
(-1575 4100) 0;
DISPLAY LEFT (-1575 4100);
DISPLAY 1.021277 (-1575 4100);
PAINT PURPLE (-1575 4100);
FORCENOTE
TO PCH PCIEUP
(-875 1325) 0;
DISPLAY LEFT (-875 1325);
DISPLAY 1.021277 (-875 1325);
PAINT PURPLE (-875 1325);
FORCENOTE
CPU0 TO PCH PCIEUP TX CAPS
(-2650 2700) 0;
DISPLAY LEFT (-2650 2700);
DISPLAY 1.021277 (-2650 2700);
PAINT PURPLE (-2650 2700);
FORCENOTE
DE NOTE:
(-2650 2775) 0;
DISPLAY LEFT (-2650 2775);
DISPLAY 1.021277 (-2650 2775);
PAINT PURPLE (-2650 2775);
FORCENOTE
FROM CPU0
(-3450 1825) 0;
DISPLAY LEFT (-3450 1825);
DISPLAY 1.021277 (-3450 1825);
PAINT PURPLE (-3450 1825);
QUIT
